FILE_TYPE = MACRO_DRAWING;
SET COLOR_WIRE YELLOW;
SET COLOR_PROP MONO;
SET COLOR_DOT WHITE;
SET COLOR_ARC YELLOW;
SET COLOR_BODY GREEN;
SET COLOR_NOTE MONO;
SET PROP_DISPLAY VALUE;
SET PAGE_NUMBER P48;
FORCEADD OFFPAGE..3
(1600 5200);
FORCEPROP 2 LAST $XR1 47 
J 0
(1904 5200);
DISPLAY 0.638298 (1904 5200);
PAINT MONO (1904 5200);
FORCEPROP 2 LAST $XR0 25 
J 0
(1814 5200);
DISPLAY 0.638298 (1814 5200);
PAINT MONO (1814 5200);
FORCEPROP 2 LAST CDS_LIB mstr_standard
J 0
(1600 5200);
DISPLAY 0.787234 (1600 5200);
PAINT MONO (1600 5200);
DISPLAY INVISIBLE (1600 5200);
FORCEPROP 1 LAST OFFPAGE TRUE
J 0
(1925 5075);
DISPLAY 0.936170 (1925 5075);
PAINT GREEN (1925 5075);
DISPLAY INVISIBLE (1925 5075);
FORCEPROP 1 LAST COMMENT_BODY TRUE
J 0
(1550 5100);
DISPLAY 0.936170 (1550 5100);
PAINT GREEN (1550 5100);
DISPLAY INVISIBLE (1550 5100);
FORCEPROP 2 LAST PATH I1
J 0
(1800 5275);
DISPLAY 0.787234 (1800 5275);
PAINT MONO (1800 5275);
DISPLAY INVISIBLE (1800 5275);
FORCEADD TAP..6
R 2
(700 4850);
FORCEPROP 3 LASTPIN (650 4850) SIG_NAME M_C_DQS_DP<14>
J 0
(660 4860);
DISPLAY 0.659574 (660 4860);
PAINT MONO (660 4860);
DISPLAY INVISIBLE (660 4860);
FORCEPROP 1 LASTPIN (650 4850) BN 14
J 2
(700 4860);
DISPLAY 0.617021 (700 4860);
PAINT PINK (700 4860);
FORCEPROP 2 LAST CDS_LIB mstr_standard
J 0
(700 4850);
DISPLAY 0.787234 (700 4850);
PAINT MONO (700 4850);
DISPLAY INVISIBLE (700 4850);
FORCEPROP 1 LAST BODY_TYPE PLUMBING
J 2
(700 4800);
DISPLAY 1.234043 (700 4800);
PAINT GREEN (700 4800);
DISPLAY INVISIBLE (700 4800);
FORCEPROP 1 LAST HDL_TAP TRUE
J 2
(375 4725);
DISPLAY 1.234043 (375 4725);
PAINT WHITE (375 4725);
DISPLAY INVISIBLE (375 4725);
FORCEPROP 1 LAST PATH I10
J 2
(700 4850);
DISPLAY 0.936170 (700 4850);
PAINT GREEN (700 4850);
DISPLAY INVISIBLE (700 4850);
FORCEADD TAP..6
R 2
(-1650 2100);
FORCEPROP 3 LASTPIN (-1700 2100) SIG_NAME M_C_DQ<8>
J 0
(-1690 2110);
DISPLAY 0.659574 (-1690 2110);
PAINT MONO (-1690 2110);
DISPLAY INVISIBLE (-1690 2110);
FORCEPROP 1 LASTPIN (-1700 2100) BN 8
J 2
(-1650 2110);
DISPLAY 0.617021 (-1650 2110);
PAINT PINK (-1650 2110);
FORCEPROP 2 LAST CDS_LIB mstr_standard
J 2
(-1650 2100);
DISPLAY 0.787234 (-1650 2100);
PAINT MONO (-1650 2100);
DISPLAY INVISIBLE (-1650 2100);
FORCEPROP 1 LAST BODY_TYPE PLUMBING
J 2
(-1650 2050);
DISPLAY 1.234043 (-1650 2050);
PAINT GREEN (-1650 2050);
DISPLAY INVISIBLE (-1650 2050);
FORCEPROP 1 LAST HDL_TAP TRUE
J 2
(-1975 1975);
DISPLAY 1.234043 (-1975 1975);
PAINT GREEN (-1975 1975);
DISPLAY INVISIBLE (-1975 1975);
FORCEPROP 1 LAST PATH I100
J 2
(-1650 2100);
DISPLAY 0.936170 (-1650 2100);
PAINT GREEN (-1650 2100);
DISPLAY INVISIBLE (-1650 2100);
FORCEADD TAP..6
R 2
(-1650 2200);
FORCEPROP 3 LASTPIN (-1700 2200) SIG_NAME M_C_DQ<10>
J 0
(-1690 2210);
DISPLAY 0.659574 (-1690 2210);
PAINT MONO (-1690 2210);
DISPLAY INVISIBLE (-1690 2210);
FORCEPROP 1 LASTPIN (-1700 2200) BN 10
J 2
(-1650 2210);
DISPLAY 0.617021 (-1650 2210);
PAINT PINK (-1650 2210);
FORCEPROP 2 LAST CDS_LIB mstr_standard
J 2
(-1650 2200);
DISPLAY 0.787234 (-1650 2200);
PAINT MONO (-1650 2200);
DISPLAY INVISIBLE (-1650 2200);
FORCEPROP 1 LAST BODY_TYPE PLUMBING
J 2
(-1650 2150);
DISPLAY 1.234043 (-1650 2150);
PAINT GREEN (-1650 2150);
DISPLAY INVISIBLE (-1650 2150);
FORCEPROP 1 LAST HDL_TAP TRUE
J 2
(-1975 2075);
DISPLAY 1.234043 (-1975 2075);
PAINT GREEN (-1975 2075);
DISPLAY INVISIBLE (-1975 2075);
FORCEPROP 1 LAST PATH I101
J 2
(-1650 2200);
DISPLAY 0.936170 (-1650 2200);
PAINT GREEN (-1650 2200);
DISPLAY INVISIBLE (-1650 2200);
FORCEADD TAP..6
R 2
(-1650 2150);
FORCEPROP 3 LASTPIN (-1700 2150) SIG_NAME M_C_DQ<9>
J 0
(-1690 2160);
DISPLAY 0.659574 (-1690 2160);
PAINT MONO (-1690 2160);
DISPLAY INVISIBLE (-1690 2160);
FORCEPROP 1 LASTPIN (-1700 2150) BN 9
J 2
(-1650 2160);
DISPLAY 0.617021 (-1650 2160);
PAINT PINK (-1650 2160);
FORCEPROP 2 LAST CDS_LIB mstr_standard
J 2
(-1650 2150);
DISPLAY 0.787234 (-1650 2150);
PAINT MONO (-1650 2150);
DISPLAY INVISIBLE (-1650 2150);
FORCEPROP 1 LAST BODY_TYPE PLUMBING
J 2
(-1650 2100);
DISPLAY 1.234043 (-1650 2100);
PAINT GREEN (-1650 2100);
DISPLAY INVISIBLE (-1650 2100);
FORCEPROP 1 LAST HDL_TAP TRUE
J 2
(-1975 2025);
DISPLAY 1.234043 (-1975 2025);
PAINT GREEN (-1975 2025);
DISPLAY INVISIBLE (-1975 2025);
FORCEPROP 1 LAST PATH I102
J 2
(-1650 2150);
DISPLAY 0.936170 (-1650 2150);
PAINT GREEN (-1650 2150);
DISPLAY INVISIBLE (-1650 2150);
FORCEADD TAP..6
R 2
(-1650 1950);
FORCEPROP 3 LASTPIN (-1700 1950) SIG_NAME M_C_DQ<5>
J 0
(-1690 1960);
DISPLAY 0.659574 (-1690 1960);
PAINT MONO (-1690 1960);
DISPLAY INVISIBLE (-1690 1960);
FORCEPROP 1 LASTPIN (-1700 1950) BN 5
J 2
(-1650 1960);
DISPLAY 0.617021 (-1650 1960);
PAINT PINK (-1650 1960);
FORCEPROP 2 LAST CDS_LIB mstr_standard
J 2
(-1650 1950);
DISPLAY 0.787234 (-1650 1950);
PAINT MONO (-1650 1950);
DISPLAY INVISIBLE (-1650 1950);
FORCEPROP 1 LAST BODY_TYPE PLUMBING
J 2
(-1650 1900);
DISPLAY 1.234043 (-1650 1900);
PAINT GREEN (-1650 1900);
DISPLAY INVISIBLE (-1650 1900);
FORCEPROP 1 LAST HDL_TAP TRUE
J 2
(-1975 1825);
DISPLAY 1.234043 (-1975 1825);
PAINT GREEN (-1975 1825);
DISPLAY INVISIBLE (-1975 1825);
FORCEPROP 1 LAST PATH I103
J 2
(-1650 1950);
DISPLAY 0.936170 (-1650 1950);
PAINT GREEN (-1650 1950);
DISPLAY INVISIBLE (-1650 1950);
FORCEADD TAP..6
R 2
(-1650 2000);
FORCEPROP 3 LASTPIN (-1700 2000) SIG_NAME M_C_DQ<6>
J 0
(-1690 2010);
DISPLAY 0.659574 (-1690 2010);
PAINT MONO (-1690 2010);
DISPLAY INVISIBLE (-1690 2010);
FORCEPROP 1 LASTPIN (-1700 2000) BN 6
J 2
(-1650 2010);
DISPLAY 0.617021 (-1650 2010);
PAINT PINK (-1650 2010);
FORCEPROP 2 LAST CDS_LIB mstr_standard
J 2
(-1650 2000);
DISPLAY 0.787234 (-1650 2000);
PAINT MONO (-1650 2000);
DISPLAY INVISIBLE (-1650 2000);
FORCEPROP 1 LAST BODY_TYPE PLUMBING
J 2
(-1650 1950);
DISPLAY 1.234043 (-1650 1950);
PAINT GREEN (-1650 1950);
DISPLAY INVISIBLE (-1650 1950);
FORCEPROP 1 LAST HDL_TAP TRUE
J 2
(-1975 1875);
DISPLAY 1.234043 (-1975 1875);
PAINT GREEN (-1975 1875);
DISPLAY INVISIBLE (-1975 1875);
FORCEPROP 1 LAST PATH I104
J 2
(-1650 2000);
DISPLAY 0.936170 (-1650 2000);
PAINT GREEN (-1650 2000);
DISPLAY INVISIBLE (-1650 2000);
FORCEADD TAP..6
R 2
(-1650 2050);
FORCEPROP 3 LASTPIN (-1700 2050) SIG_NAME M_C_DQ<7>
J 0
(-1690 2060);
DISPLAY 0.659574 (-1690 2060);
PAINT MONO (-1690 2060);
DISPLAY INVISIBLE (-1690 2060);
FORCEPROP 1 LASTPIN (-1700 2050) BN 7
J 2
(-1650 2060);
DISPLAY 0.617021 (-1650 2060);
PAINT PINK (-1650 2060);
FORCEPROP 2 LAST CDS_LIB mstr_standard
J 2
(-1650 2050);
DISPLAY 0.787234 (-1650 2050);
PAINT MONO (-1650 2050);
DISPLAY INVISIBLE (-1650 2050);
FORCEPROP 1 LAST BODY_TYPE PLUMBING
J 2
(-1650 2000);
DISPLAY 1.234043 (-1650 2000);
PAINT GREEN (-1650 2000);
DISPLAY INVISIBLE (-1650 2000);
FORCEPROP 1 LAST HDL_TAP TRUE
J 2
(-1975 1925);
DISPLAY 1.234043 (-1975 1925);
PAINT GREEN (-1975 1925);
DISPLAY INVISIBLE (-1975 1925);
FORCEPROP 1 LAST PATH I105
J 2
(-1650 2050);
DISPLAY 0.936170 (-1650 2050);
PAINT GREEN (-1650 2050);
DISPLAY INVISIBLE (-1650 2050);
FORCEADD TAP..6
R 2
(-1650 1900);
FORCEPROP 3 LASTPIN (-1700 1900) SIG_NAME M_C_DQ<4>
J 0
(-1690 1910);
DISPLAY 0.659574 (-1690 1910);
PAINT MONO (-1690 1910);
DISPLAY INVISIBLE (-1690 1910);
FORCEPROP 1 LASTPIN (-1700 1900) BN 4
J 2
(-1650 1910);
DISPLAY 0.617021 (-1650 1910);
PAINT PINK (-1650 1910);
FORCEPROP 2 LAST CDS_LIB mstr_standard
J 2
(-1650 1900);
DISPLAY 0.787234 (-1650 1900);
PAINT MONO (-1650 1900);
DISPLAY INVISIBLE (-1650 1900);
FORCEPROP 1 LAST BODY_TYPE PLUMBING
J 2
(-1650 1850);
DISPLAY 1.234043 (-1650 1850);
PAINT GREEN (-1650 1850);
DISPLAY INVISIBLE (-1650 1850);
FORCEPROP 1 LAST HDL_TAP TRUE
J 2
(-1975 1775);
DISPLAY 1.234043 (-1975 1775);
PAINT GREEN (-1975 1775);
DISPLAY INVISIBLE (-1975 1775);
FORCEPROP 1 LAST PATH I106
J 2
(-1650 1900);
DISPLAY 0.936170 (-1650 1900);
PAINT GREEN (-1650 1900);
DISPLAY INVISIBLE (-1650 1900);
FORCEADD TAP..6
R 2
(-1650 1850);
FORCEPROP 3 LASTPIN (-1700 1850) SIG_NAME M_C_DQ<3>
J 0
(-1690 1860);
DISPLAY 0.659574 (-1690 1860);
PAINT MONO (-1690 1860);
DISPLAY INVISIBLE (-1690 1860);
FORCEPROP 1 LASTPIN (-1700 1850) BN 3
J 2
(-1650 1860);
DISPLAY 0.617021 (-1650 1860);
PAINT PINK (-1650 1860);
FORCEPROP 2 LAST CDS_LIB mstr_standard
J 2
(-1650 1850);
DISPLAY 0.787234 (-1650 1850);
PAINT MONO (-1650 1850);
DISPLAY INVISIBLE (-1650 1850);
FORCEPROP 1 LAST BODY_TYPE PLUMBING
J 2
(-1650 1800);
DISPLAY 1.234043 (-1650 1800);
PAINT GREEN (-1650 1800);
DISPLAY INVISIBLE (-1650 1800);
FORCEPROP 1 LAST HDL_TAP TRUE
J 2
(-1975 1725);
DISPLAY 1.234043 (-1975 1725);
PAINT GREEN (-1975 1725);
DISPLAY INVISIBLE (-1975 1725);
FORCEPROP 1 LAST PATH I107
J 2
(-1650 1850);
DISPLAY 0.936170 (-1650 1850);
PAINT GREEN (-1650 1850);
DISPLAY INVISIBLE (-1650 1850);
FORCEADD TAP..6
R 2
(-1650 1750);
FORCEPROP 3 LASTPIN (-1700 1750) SIG_NAME M_C_DQ<1>
J 0
(-1690 1760);
DISPLAY 0.659574 (-1690 1760);
PAINT MONO (-1690 1760);
DISPLAY INVISIBLE (-1690 1760);
FORCEPROP 1 LASTPIN (-1700 1750) BN 1
J 2
(-1650 1760);
DISPLAY 0.617021 (-1650 1760);
PAINT PINK (-1650 1760);
FORCEPROP 2 LAST CDS_LIB mstr_standard
J 2
(-1650 1750);
DISPLAY 0.787234 (-1650 1750);
PAINT MONO (-1650 1750);
DISPLAY INVISIBLE (-1650 1750);
FORCEPROP 1 LAST BODY_TYPE PLUMBING
J 2
(-1650 1700);
DISPLAY 1.234043 (-1650 1700);
PAINT GREEN (-1650 1700);
DISPLAY INVISIBLE (-1650 1700);
FORCEPROP 1 LAST HDL_TAP TRUE
J 2
(-1975 1625);
DISPLAY 1.234043 (-1975 1625);
PAINT GREEN (-1975 1625);
DISPLAY INVISIBLE (-1975 1625);
FORCEPROP 1 LAST PATH I108
J 2
(-1650 1750);
DISPLAY 0.936170 (-1650 1750);
PAINT GREEN (-1650 1750);
DISPLAY INVISIBLE (-1650 1750);
FORCEADD TAP..6
R 2
(-1650 1800);
FORCEPROP 3 LASTPIN (-1700 1800) SIG_NAME M_C_DQ<2>
J 0
(-1690 1810);
DISPLAY 0.659574 (-1690 1810);
PAINT MONO (-1690 1810);
DISPLAY INVISIBLE (-1690 1810);
FORCEPROP 1 LASTPIN (-1700 1800) BN 2
J 2
(-1650 1810);
DISPLAY 0.617021 (-1650 1810);
PAINT PINK (-1650 1810);
FORCEPROP 2 LAST CDS_LIB mstr_standard
J 2
(-1650 1800);
DISPLAY 0.787234 (-1650 1800);
PAINT MONO (-1650 1800);
DISPLAY INVISIBLE (-1650 1800);
FORCEPROP 1 LAST BODY_TYPE PLUMBING
J 2
(-1650 1750);
DISPLAY 1.234043 (-1650 1750);
PAINT GREEN (-1650 1750);
DISPLAY INVISIBLE (-1650 1750);
FORCEPROP 1 LAST HDL_TAP TRUE
J 2
(-1975 1675);
DISPLAY 1.234043 (-1975 1675);
PAINT GREEN (-1975 1675);
DISPLAY INVISIBLE (-1975 1675);
FORCEPROP 1 LAST PATH I109
J 2
(-1650 1800);
DISPLAY 0.936170 (-1650 1800);
PAINT GREEN (-1650 1800);
DISPLAY INVISIBLE (-1650 1800);
FORCEADD TAP..6
R 2
(-1650 1700);
FORCEPROP 3 LASTPIN (-1700 1700) SIG_NAME M_C_DQ<0>
J 0
(-1690 1710);
DISPLAY 0.659574 (-1690 1710);
PAINT MONO (-1690 1710);
DISPLAY INVISIBLE (-1690 1710);
FORCEPROP 1 LASTPIN (-1700 1700) BN 0
J 2
(-1650 1710);
DISPLAY 0.617021 (-1650 1710);
PAINT PINK (-1650 1710);
FORCEPROP 2 LAST CDS_LIB mstr_standard
J 2
(-1650 1700);
DISPLAY 0.787234 (-1650 1700);
PAINT MONO (-1650 1700);
DISPLAY INVISIBLE (-1650 1700);
FORCEPROP 1 LAST BODY_TYPE PLUMBING
J 2
(-1650 1650);
DISPLAY 1.234043 (-1650 1650);
PAINT GREEN (-1650 1650);
DISPLAY INVISIBLE (-1650 1650);
FORCEPROP 1 LAST HDL_TAP TRUE
J 2
(-1975 1575);
DISPLAY 1.234043 (-1975 1575);
PAINT GREEN (-1975 1575);
DISPLAY INVISIBLE (-1975 1575);
FORCEPROP 1 LAST PATH I110
J 2
(-1650 1700);
DISPLAY 0.936170 (-1650 1700);
PAINT GREEN (-1650 1700);
DISPLAY INVISIBLE (-1650 1700);
FORCEADD SCONN288_H44441003..1
(-2400 3200);
FORCEPROP 1 LAST PART_NUMBER H44441-003
J 0
(-2850 1200);
DISPLAY 0.617021 (-2850 1200);
PAINT BLUE (-2850 1200);
FORCEPROP 2 LASTPIN (-2900 1700) $PN 146
J 2
(-2910 1710);
DISPLAY 0.617021 (-2910 1710);
PAINT ORANGE (-2910 1710);
FORCEPROP 2 LASTPIN (-2900 2050) $PN 284
J 2
(-2910 2060);
DISPLAY 0.617021 (-2910 2060);
PAINT ORANGE (-2910 2060);
FORCEPROP 2 LASTPIN (-2900 1850) $PN 285
J 2
(-2910 1860);
DISPLAY 0.617021 (-2910 1860);
PAINT ORANGE (-2910 1860);
FORCEPROP 2 LASTPIN (-2900 1800) $PN 141
J 2
(-2910 1810);
DISPLAY 0.617021 (-2910 1810);
PAINT ORANGE (-2910 1810);
FORCEPROP 2 LASTPIN (-2900 1400) $PN 230
J 2
(-2910 1410);
DISPLAY 0.617021 (-2910 1410);
PAINT ORANGE (-2910 1410);
FORCEPROP 2 LASTPIN (-2900 2000) $PN 238
J 2
(-2910 2010);
DISPLAY 0.617021 (-2910 2010);
PAINT ORANGE (-2910 2010);
FORCEPROP 2 LASTPIN (-2900 1950) $PN 140
J 2
(-2910 1960);
DISPLAY 0.617021 (-2910 1960);
PAINT ORANGE (-2910 1960);
FORCEPROP 2 LASTPIN (-2900 1900) $PN 139
J 2
(-2910 1910);
DISPLAY 0.617021 (-2910 1910);
PAINT ORANGE (-2910 1910);
FORCEPROP 2 LASTPIN (-2900 3350) $PN 237
J 2
(-2910 3360);
DISPLAY 0.617021 (-2910 3360);
PAINT ORANGE (-2910 3360);
FORCEPROP 2 LASTPIN (-2900 3300) $PN 93
J 2
(-2910 3310);
DISPLAY 0.617021 (-2910 3310);
PAINT ORANGE (-2910 3310);
FORCEPROP 2 LASTPIN (-2900 3250) $PN 89
J 2
(-2910 3260);
DISPLAY 0.617021 (-2910 3260);
PAINT ORANGE (-2910 3260);
FORCEPROP 2 LASTPIN (-2900 3200) $PN 84
J 2
(-2910 3210);
DISPLAY 0.617021 (-2910 3210);
PAINT ORANGE (-2910 3210);
FORCEPROP 2 LASTPIN (-2900 1600) $PN 144
J 2
(-2910 1610);
DISPLAY 0.617021 (-2910 1610);
PAINT ORANGE (-2910 1610);
FORCEPROP 2 LASTPIN (-2900 1550) $PN 227
J 2
(-2910 1560);
DISPLAY 0.617021 (-2910 1560);
PAINT ORANGE (-2910 1560);
FORCEPROP 2 LASTPIN (-2900 1500) $PN 205
J 2
(-2910 1510);
DISPLAY 0.617021 (-2910 1510);
PAINT ORANGE (-2910 1510);
FORCEPROP 2 LASTPIN (-2900 2300) $PN 58
J 2
(-2910 2310);
DISPLAY 0.617021 (-2910 2310);
PAINT ORANGE (-2910 2310);
FORCEPROP 2 LASTPIN (-2900 2350) $PN 222
J 2
(-2910 2360);
DISPLAY 0.617021 (-2910 2360);
PAINT ORANGE (-2910 2360);
FORCEPROP 2 LASTPIN (-2900 2950) $PN 91
J 2
(-2910 2960);
DISPLAY 0.617021 (-2910 2960);
PAINT ORANGE (-2910 2960);
FORCEPROP 2 LASTPIN (-2900 2900) $PN 87
J 2
(-2910 2910);
DISPLAY 0.617021 (-2910 2910);
PAINT ORANGE (-2910 2910);
FORCEPROP 2 LASTPIN (-2900 2250) $PN 78
J 2
(-2910 2260);
DISPLAY 0.617021 (-2910 2260);
PAINT ORANGE (-2910 2260);
FORCEPROP 2 LASTPIN (-1900 4850) $PN 280
J 0
(-1890 4860);
DISPLAY 0.617021 (-1890 4860);
PAINT ORANGE (-1890 4860);
FORCEPROP 2 LASTPIN (-1900 4800) $PN 135
J 0
(-1890 4810);
DISPLAY 0.617021 (-1890 4810);
PAINT ORANGE (-1890 4810);
FORCEPROP 2 LASTPIN (-1900 4750) $PN 273
J 0
(-1890 4760);
DISPLAY 0.617021 (-1890 4760);
PAINT ORANGE (-1890 4760);
FORCEPROP 2 LASTPIN (-1900 4700) $PN 128
J 0
(-1890 4710);
DISPLAY 0.617021 (-1890 4710);
PAINT ORANGE (-1890 4710);
FORCEPROP 2 LASTPIN (-1900 4650) $PN 282
J 0
(-1890 4660);
DISPLAY 0.617021 (-1890 4660);
PAINT ORANGE (-1890 4660);
FORCEPROP 2 LASTPIN (-1900 4600) $PN 137
J 0
(-1890 4610);
DISPLAY 0.617021 (-1890 4610);
PAINT ORANGE (-1890 4610);
FORCEPROP 2 LASTPIN (-1900 4550) $PN 275
J 0
(-1890 4560);
DISPLAY 0.617021 (-1890 4560);
PAINT ORANGE (-1890 4560);
FORCEPROP 2 LASTPIN (-1900 4500) $PN 130
J 0
(-1890 4510);
DISPLAY 0.617021 (-1890 4510);
PAINT ORANGE (-1890 4510);
FORCEPROP 2 LASTPIN (-1900 4400) $PN 124
J 0
(-1890 4410);
DISPLAY 0.617021 (-1890 4410);
PAINT ORANGE (-1890 4410);
FORCEPROP 2 LASTPIN (-1900 4350) $PN 262
J 0
(-1890 4360);
DISPLAY 0.617021 (-1890 4360);
PAINT ORANGE (-1890 4360);
FORCEPROP 2 LASTPIN (-1900 4300) $PN 117
J 0
(-1890 4310);
DISPLAY 0.617021 (-1890 4310);
PAINT ORANGE (-1890 4310);
FORCEPROP 2 LASTPIN (-1900 4250) $PN 271
J 0
(-1890 4260);
DISPLAY 0.617021 (-1890 4260);
PAINT ORANGE (-1890 4260);
FORCEPROP 2 LASTPIN (-1900 4200) $PN 126
J 0
(-1890 4210);
DISPLAY 0.617021 (-1890 4210);
PAINT ORANGE (-1890 4210);
FORCEPROP 2 LASTPIN (-1900 4150) $PN 264
J 0
(-1890 4160);
DISPLAY 0.617021 (-1890 4160);
PAINT ORANGE (-1890 4160);
FORCEPROP 2 LASTPIN (-1900 4100) $PN 119
J 0
(-1890 4110);
DISPLAY 0.617021 (-1890 4110);
PAINT ORANGE (-1890 4110);
FORCEPROP 2 LASTPIN (-1900 4050) $PN 258
J 0
(-1890 4060);
DISPLAY 0.617021 (-1890 4060);
PAINT ORANGE (-1890 4060);
FORCEPROP 2 LASTPIN (-1900 4000) $PN 113
J 0
(-1890 4010);
DISPLAY 0.617021 (-1890 4010);
PAINT ORANGE (-1890 4010);
FORCEPROP 2 LASTPIN (-1900 3950) $PN 251
J 0
(-1890 3960);
DISPLAY 0.617021 (-1890 3960);
PAINT ORANGE (-1890 3960);
FORCEPROP 2 LASTPIN (-1900 3850) $PN 260
J 0
(-1890 3860);
DISPLAY 0.617021 (-1890 3860);
PAINT ORANGE (-1890 3860);
FORCEPROP 2 LASTPIN (-1900 3800) $PN 115
J 0
(-1890 3810);
DISPLAY 0.617021 (-1890 3810);
PAINT ORANGE (-1890 3810);
FORCEPROP 2 LASTPIN (-1900 3750) $PN 253
J 0
(-1890 3760);
DISPLAY 0.617021 (-1890 3760);
PAINT ORANGE (-1890 3760);
FORCEPROP 2 LASTPIN (-1900 3700) $PN 108
J 0
(-1890 3710);
DISPLAY 0.617021 (-1890 3710);
PAINT ORANGE (-1890 3710);
FORCEPROP 2 LASTPIN (-1900 3650) $PN 247
J 0
(-1890 3660);
DISPLAY 0.617021 (-1890 3660);
PAINT ORANGE (-1890 3660);
FORCEPROP 2 LASTPIN (-1900 3600) $PN 102
J 0
(-1890 3610);
DISPLAY 0.617021 (-1890 3610);
PAINT ORANGE (-1890 3610);
FORCEPROP 2 LASTPIN (-1900 3550) $PN 240
J 0
(-1890 3560);
DISPLAY 0.617021 (-1890 3560);
PAINT ORANGE (-1890 3560);
FORCEPROP 2 LASTPIN (-1900 3500) $PN 95
J 0
(-1890 3510);
DISPLAY 0.617021 (-1890 3510);
PAINT ORANGE (-1890 3510);
FORCEPROP 2 LASTPIN (-1900 3350) $PN 242
J 0
(-1890 3360);
DISPLAY 0.617021 (-1890 3360);
PAINT ORANGE (-1890 3360);
FORCEPROP 2 LASTPIN (-1900 3300) $PN 97
J 0
(-1890 3310);
DISPLAY 0.617021 (-1890 3310);
PAINT ORANGE (-1890 3310);
FORCEPROP 2 LASTPIN (-1900 3250) $PN 188
J 0
(-1890 3260);
DISPLAY 0.617021 (-1890 3260);
PAINT ORANGE (-1890 3260);
FORCEPROP 2 LASTPIN (-1900 3200) $PN 43
J 0
(-1890 3210);
DISPLAY 0.617021 (-1890 3210);
PAINT ORANGE (-1890 3210);
FORCEPROP 2 LASTPIN (-1900 3150) $PN 181
J 0
(-1890 3160);
DISPLAY 0.617021 (-1890 3160);
PAINT ORANGE (-1890 3160);
FORCEPROP 2 LASTPIN (-1900 3100) $PN 36
J 0
(-1890 3110);
DISPLAY 0.617021 (-1890 3110);
PAINT ORANGE (-1890 3110);
FORCEPROP 2 LASTPIN (-1900 3050) $PN 190
J 0
(-1890 3060);
DISPLAY 0.617021 (-1890 3060);
PAINT ORANGE (-1890 3060);
FORCEPROP 2 LASTPIN (-1900 3000) $PN 45
J 0
(-1890 3010);
DISPLAY 0.617021 (-1890 3010);
PAINT ORANGE (-1890 3010);
FORCEPROP 2 LASTPIN (-1900 2950) $PN 183
J 0
(-1890 2960);
DISPLAY 0.617021 (-1890 2960);
PAINT ORANGE (-1890 2960);
FORCEPROP 2 LASTPIN (-1900 2900) $PN 38
J 0
(-1890 2910);
DISPLAY 0.617021 (-1890 2910);
PAINT ORANGE (-1890 2910);
FORCEPROP 2 LASTPIN (-1900 2850) $PN 177
J 0
(-1890 2860);
DISPLAY 0.617021 (-1890 2860);
PAINT ORANGE (-1890 2860);
FORCEPROP 2 LASTPIN (-1900 2800) $PN 32
J 0
(-1890 2810);
DISPLAY 0.617021 (-1890 2810);
PAINT ORANGE (-1890 2810);
FORCEPROP 2 LASTPIN (-1900 2750) $PN 170
J 0
(-1890 2760);
DISPLAY 0.617021 (-1890 2760);
PAINT ORANGE (-1890 2760);
FORCEPROP 2 LASTPIN (-1900 2700) $PN 25
J 0
(-1890 2710);
DISPLAY 0.617021 (-1890 2710);
PAINT ORANGE (-1890 2710);
FORCEPROP 2 LASTPIN (-1900 2650) $PN 179
J 0
(-1890 2660);
DISPLAY 0.617021 (-1890 2660);
PAINT ORANGE (-1890 2660);
FORCEPROP 2 LASTPIN (-1900 2600) $PN 34
J 0
(-1890 2610);
DISPLAY 0.617021 (-1890 2610);
PAINT ORANGE (-1890 2610);
FORCEPROP 2 LASTPIN (-1900 2550) $PN 172
J 0
(-1890 2560);
DISPLAY 0.617021 (-1890 2560);
PAINT ORANGE (-1890 2560);
FORCEPROP 2 LASTPIN (-1900 2500) $PN 27
J 0
(-1890 2510);
DISPLAY 0.617021 (-1890 2510);
PAINT ORANGE (-1890 2510);
FORCEPROP 2 LASTPIN (-1900 2450) $PN 166
J 0
(-1890 2460);
DISPLAY 0.617021 (-1890 2460);
PAINT ORANGE (-1890 2460);
FORCEPROP 2 LASTPIN (-1900 2400) $PN 21
J 0
(-1890 2410);
DISPLAY 0.617021 (-1890 2410);
PAINT ORANGE (-1890 2410);
FORCEPROP 2 LASTPIN (-1900 2350) $PN 159
J 0
(-1890 2360);
DISPLAY 0.617021 (-1890 2360);
PAINT ORANGE (-1890 2360);
FORCEPROP 2 LASTPIN (-1900 2300) $PN 14
J 0
(-1890 2310);
DISPLAY 0.617021 (-1890 2310);
PAINT ORANGE (-1890 2310);
FORCEPROP 2 LASTPIN (-1900 2250) $PN 168
J 0
(-1890 2260);
DISPLAY 0.617021 (-1890 2260);
PAINT ORANGE (-1890 2260);
FORCEPROP 2 LASTPIN (-1900 2200) $PN 23
J 0
(-1890 2210);
DISPLAY 0.617021 (-1890 2210);
PAINT ORANGE (-1890 2210);
FORCEPROP 2 LASTPIN (-1900 2150) $PN 161
J 0
(-1890 2160);
DISPLAY 0.617021 (-1890 2160);
PAINT ORANGE (-1890 2160);
FORCEPROP 2 LASTPIN (-1900 2100) $PN 16
J 0
(-1890 2110);
DISPLAY 0.617021 (-1890 2110);
PAINT ORANGE (-1890 2110);
FORCEPROP 2 LASTPIN (-1900 2050) $PN 155
J 0
(-1890 2060);
DISPLAY 0.617021 (-1890 2060);
PAINT ORANGE (-1890 2060);
FORCEPROP 2 LASTPIN (-1900 2000) $PN 10
J 0
(-1890 2010);
DISPLAY 0.617021 (-1890 2010);
PAINT ORANGE (-1890 2010);
FORCEPROP 2 LASTPIN (-1900 1950) $PN 148
J 0
(-1890 1960);
DISPLAY 0.617021 (-1890 1960);
PAINT ORANGE (-1890 1960);
FORCEPROP 2 LASTPIN (-1900 1900) $PN 3
J 0
(-1890 1910);
DISPLAY 0.617021 (-1890 1910);
PAINT ORANGE (-1890 1910);
FORCEPROP 2 LASTPIN (-1900 1850) $PN 157
J 0
(-1890 1860);
DISPLAY 0.617021 (-1890 1860);
PAINT ORANGE (-1890 1860);
FORCEPROP 2 LASTPIN (-1900 1800) $PN 12
J 0
(-1890 1810);
DISPLAY 0.617021 (-1890 1810);
PAINT ORANGE (-1890 1810);
FORCEPROP 2 LASTPIN (-1900 1750) $PN 150
J 0
(-1890 1760);
DISPLAY 0.617021 (-1890 1760);
PAINT ORANGE (-1890 1760);
FORCEPROP 2 LASTPIN (-1900 1700) $PN 5
J 0
(-1890 1710);
DISPLAY 0.617021 (-1890 1710);
PAINT ORANGE (-1890 1710);
FORCEPROP 2 LASTPIN (-2900 3100) $PN 203
J 2
(-2910 3110);
DISPLAY 0.617021 (-2910 3110);
PAINT ORANGE (-2910 3110);
FORCEPROP 2 LASTPIN (-2900 3050) $PN 60
J 2
(-2910 3060);
DISPLAY 0.617021 (-2910 3060);
PAINT ORANGE (-2910 3060);
FORCEPROP 2 LASTPIN (-2900 3650) $PN 218
J 2
(-2910 3660);
DISPLAY 0.617021 (-2910 3660);
PAINT ORANGE (-2910 3660);
FORCEPROP 2 LASTPIN (-2900 3600) $PN 219
J 2
(-2910 3610);
DISPLAY 0.617021 (-2910 3610);
PAINT ORANGE (-2910 3610);
FORCEPROP 2 LASTPIN (-2900 3550) $PN 74
J 2
(-2910 3560);
DISPLAY 0.617021 (-2910 3560);
PAINT ORANGE (-2910 3560);
FORCEPROP 2 LASTPIN (-2900 3500) $PN 75
J 2
(-2910 3510);
DISPLAY 0.617021 (-2910 3510);
PAINT ORANGE (-2910 3510);
FORCEPROP 2 LASTPIN (-2900 2800) $PN 199
J 2
(-2910 2810);
DISPLAY 0.617021 (-2910 2810);
PAINT ORANGE (-2910 2810);
FORCEPROP 2 LASTPIN (-2900 2750) $PN 54
J 2
(-2910 2760);
DISPLAY 0.617021 (-2910 2760);
PAINT ORANGE (-2910 2760);
FORCEPROP 2 LASTPIN (-2900 2700) $PN 192
J 2
(-2910 2710);
DISPLAY 0.617021 (-2910 2710);
PAINT ORANGE (-2910 2710);
FORCEPROP 2 LASTPIN (-2900 2650) $PN 47
J 2
(-2910 2660);
DISPLAY 0.617021 (-2910 2660);
PAINT ORANGE (-2910 2660);
FORCEPROP 2 LASTPIN (-2900 2600) $PN 201
J 2
(-2910 2610);
DISPLAY 0.617021 (-2910 2610);
PAINT ORANGE (-2910 2610);
FORCEPROP 2 LASTPIN (-2900 2550) $PN 56
J 2
(-2910 2560);
DISPLAY 0.617021 (-2910 2560);
PAINT ORANGE (-2910 2560);
FORCEPROP 2 LASTPIN (-2900 2500) $PN 194
J 2
(-2910 2510);
DISPLAY 0.617021 (-2910 2510);
PAINT ORANGE (-2910 2510);
FORCEPROP 2 LASTPIN (-2900 2450) $PN 49
J 2
(-2910 2460);
DISPLAY 0.617021 (-2910 2460);
PAINT ORANGE (-2910 2460);
FORCEPROP 2 LASTPIN (-2900 3400) $PN 235
J 2
(-2910 3410);
DISPLAY 0.617021 (-2910 3410);
PAINT ORANGE (-2910 3410);
FORCEPROP 2 LASTPIN (-2900 3800) $PN 207
J 2
(-2910 3810);
DISPLAY 0.617021 (-2910 3810);
PAINT ORANGE (-2910 3810);
FORCEPROP 2 LASTPIN (-2900 3750) $PN 63
J 2
(-2910 3760);
DISPLAY 0.617021 (-2910 3760);
PAINT ORANGE (-2910 3760);
FORCEPROP 2 LASTPIN (-2900 2200) $PN 208
J 2
(-2910 2210);
DISPLAY 0.617021 (-2910 2210);
PAINT ORANGE (-2910 2210);
FORCEPROP 2 LASTPIN (-2900 2150) $PN 62
J 2
(-2910 2160);
DISPLAY 0.617021 (-2910 2160);
PAINT ORANGE (-2910 2160);
FORCEPROP 2 LASTPIN (-2900 4800) $PN 82
J 2
(-2910 4810);
DISPLAY 0.617021 (-2910 4810);
PAINT ORANGE (-2910 4810);
FORCEPROP 2 LASTPIN (-2900 4750) $PN 86
J 2
(-2910 4760);
DISPLAY 0.617021 (-2910 4760);
PAINT ORANGE (-2910 4760);
FORCEPROP 2 LASTPIN (-2900 4700) $PN 228
J 2
(-2910 4710);
DISPLAY 0.617021 (-2910 4710);
PAINT ORANGE (-2910 4710);
FORCEPROP 2 LASTPIN (-2900 4650) $PN 232
J 2
(-2910 4660);
DISPLAY 0.617021 (-2910 4660);
PAINT ORANGE (-2910 4660);
FORCEPROP 2 LASTPIN (-2900 4600) $PN 65
J 2
(-2910 4610);
DISPLAY 0.617021 (-2910 4610);
PAINT ORANGE (-2910 4610);
FORCEPROP 2 LASTPIN (-2900 4550) $PN 210
J 2
(-2910 4560);
DISPLAY 0.617021 (-2910 4560);
PAINT ORANGE (-2910 4560);
FORCEPROP 2 LASTPIN (-2900 4500) $PN 225
J 2
(-2910 4510);
DISPLAY 0.617021 (-2910 4510);
PAINT ORANGE (-2910 4510);
FORCEPROP 2 LASTPIN (-2900 4450) $PN 66
J 2
(-2910 4460);
DISPLAY 0.617021 (-2910 4460);
PAINT ORANGE (-2910 4460);
FORCEPROP 2 LASTPIN (-2900 4350) $PN 211
J 2
(-2910 4360);
DISPLAY 0.617021 (-2910 4360);
PAINT ORANGE (-2910 4360);
FORCEPROP 2 LASTPIN (-2900 4300) $PN 69
J 2
(-2910 4310);
DISPLAY 0.617021 (-2910 4310);
PAINT ORANGE (-2910 4310);
FORCEPROP 2 LASTPIN (-2900 4250) $PN 213
J 2
(-2910 4260);
DISPLAY 0.617021 (-2910 4260);
PAINT ORANGE (-2910 4260);
FORCEPROP 1 LAST LOCATION J6U2
J 0
(-2850 5100);
DISPLAY 0.617021 (-2850 5100);
PAINT AQUA (-2850 5100);
FORCEPROP 2 LASTPIN (-1900 4450) $PN 269
J 0
(-1890 4460);
DISPLAY 0.617021 (-1890 4460);
PAINT ORANGE (-1890 4460);
FORCEPROP 2 LASTPIN (-2900 4850) $PN 234
J 2
(-2910 4860);
DISPLAY 0.617021 (-2910 4860);
PAINT ORANGE (-2910 4860);
FORCEPROP 2 LASTPIN (-2900 4400) $PN 68
J 2
(-2910 4410);
DISPLAY 0.617021 (-2910 4410);
PAINT ORANGE (-2910 4410);
FORCEPROP 2 LASTPIN (-1900 3900) $PN 106
J 0
(-1890 3910);
DISPLAY 0.617021 (-1890 3910);
PAINT ORANGE (-1890 3910);
FORCEPROP 2 LASTPIN (-2900 3850) $PN 81
J 2
(-2910 3860);
DISPLAY 0.617021 (-2910 3860);
PAINT ORANGE (-2910 3860);
FORCEPROP 2 LASTPIN (-2900 3900) $PN 224
J 2
(-2910 3910);
DISPLAY 0.617021 (-2910 3910);
PAINT ORANGE (-2910 3910);
FORCEPROP 2 LASTPIN (-2900 4050) $PN 72
J 2
(-2910 4060);
DISPLAY 0.617021 (-2910 4060);
PAINT ORANGE (-2910 4060);
FORCEPROP 2 LASTPIN (-2900 4100) $PN 216
J 2
(-2910 4110);
DISPLAY 0.617021 (-2910 4110);
PAINT ORANGE (-2910 4110);
FORCEPROP 2 LASTPIN (-2900 4150) $PN 71
J 2
(-2910 4160);
DISPLAY 0.617021 (-2910 4160);
PAINT ORANGE (-2910 4160);
FORCEPROP 2 LASTPIN (-2900 4200) $PN 214
J 2
(-2910 4210);
DISPLAY 0.617021 (-2910 4210);
PAINT ORANGE (-2910 4210);
FORCEPROP 2 LASTPIN (-1900 3400) $PN 104
J 0
(-1890 3410);
DISPLAY 0.617021 (-1890 3410);
PAINT ORANGE (-1890 3410);
FORCEPROP 2 LASTPIN (-1900 3450) $PN 249
J 0
(-1890 3460);
DISPLAY 0.617021 (-1890 3460);
PAINT ORANGE (-1890 3460);
FORCEPROP 1 LAST MATERIAL SCONN
J 0
(-2850 5050);
DISPLAY 0.617021 (-2850 5050);
PAINT SKYBLUE (-2850 5050);
FORCEPROP 0 LAST BOM_SS NOPOP
J 0
(-2579 5100);
DISPLAY 1.021277 (-2579 5100);
PAINT BROWN (-2579 5100);
DISPLAY BOTH (-2579 5100);
FORCEPROP 2 LASTPIN (-2900 4000) $PN 79
J 2
(-2910 4010);
DISPLAY 0.617021 (-2910 4010);
PAINT ORANGE (-2910 4010);
FORCEPROP 1 LAST PACK_TYPE PIP
J 0
(-2850 5150);
PAINT SKYBLUE (-2850 5150);
DISPLAY INVISIBLE (-2850 5150);
FORCEPROP 2 LAST BOM_COST MEM
J 0
(-2400 3200);
PAINT ORANGE (-2400 3200);
DISPLAY INVISIBLE (-2400 3200);
FORCEPROP 2 LAST CDS_LIB mstr_sconn
J 0
(-2400 3200);
PAINT ORANGE (-2400 3200);
DISPLAY INVISIBLE (-2400 3200);
FORCEPROP 2 LAST SEC_TYPE PIP
J 0
(-2850 5150);
DISPLAY 1.021277 (-2850 5150);
PAINT ORANGE (-2850 5150);
DISPLAY INVISIBLE (-2850 5150);
FORCEPROP 2 LAST SEC 1
J 0
(-2850 5150);
DISPLAY 0.680851 (-2850 5150);
PAINT MONO (-2850 5150);
DISPLAY INVISIBLE (-2850 5150);
FORCEPROP 2 LAST CDS_LOCATION J6U2
J 0
(-2850 5100);
DISPLAY 0.617021 (-2850 5100);
PAINT AQUA (-2850 5100);
DISPLAY INVISIBLE (-2850 5100);
FORCEPROP 1 LAST PATH I111
J 0
(-2400 5050);
PAINT GREEN (-2400 5050);
DISPLAY INVISIBLE (-2400 5050);
FORCEPROP 2 LAST ROOM DDR4_CH_C1
J 0
(-2400 3200);
PAINT ORANGE (-2400 3200);
DISPLAY INVISIBLE (-2400 3200);
FORCEADD TAP..6
(-3150 4850);
FORCEPROP 3 LASTPIN (-3100 4850) SIG_NAME M_C_MA<17>
J 0
(-3090 4860);
DISPLAY 0.659574 (-3090 4860);
PAINT MONO (-3090 4860);
DISPLAY INVISIBLE (-3090 4860);
FORCEPROP 1 LASTPIN (-3100 4850) BN 17
J 0
(-3150 4860);
DISPLAY 0.617021 (-3150 4860);
PAINT PINK (-3150 4860);
FORCEPROP 2 LAST CDS_LIB mstr_standard
J 0
(-3150 4850);
DISPLAY 0.787234 (-3150 4850);
PAINT MONO (-3150 4850);
DISPLAY INVISIBLE (-3150 4850);
FORCEPROP 1 LAST BODY_TYPE PLUMBING
J 0
(-3150 4800);
DISPLAY 1.234043 (-3150 4800);
PAINT GREEN (-3150 4800);
DISPLAY INVISIBLE (-3150 4800);
FORCEPROP 1 LAST HDL_TAP TRUE
J 0
(-2825 4725);
DISPLAY 1.234043 (-2825 4725);
PAINT GREEN (-2825 4725);
DISPLAY INVISIBLE (-2825 4725);
FORCEPROP 1 LAST PATH I112
J 0
(-3150 4850);
DISPLAY 0.936170 (-3150 4850);
PAINT GREEN (-3150 4850);
DISPLAY INVISIBLE (-3150 4850);
FORCEADD TAP..6
(-3150 4800);
FORCEPROP 3 LASTPIN (-3100 4800) SIG_NAME M_C_MA<16>
J 0
(-3090 4810);
DISPLAY 0.659574 (-3090 4810);
PAINT MONO (-3090 4810);
DISPLAY INVISIBLE (-3090 4810);
FORCEPROP 1 LASTPIN (-3100 4800) BN 16
J 0
(-3150 4810);
DISPLAY 0.617021 (-3150 4810);
PAINT PINK (-3150 4810);
FORCEPROP 2 LAST CDS_LIB mstr_standard
J 2
(-3150 4800);
DISPLAY 0.787234 (-3150 4800);
PAINT MONO (-3150 4800);
DISPLAY INVISIBLE (-3150 4800);
FORCEPROP 1 LAST BODY_TYPE PLUMBING
J 0
(-3150 4750);
DISPLAY 1.234043 (-3150 4750);
PAINT GREEN (-3150 4750);
DISPLAY INVISIBLE (-3150 4750);
FORCEPROP 1 LAST HDL_TAP TRUE
J 0
(-2825 4675);
DISPLAY 1.234043 (-2825 4675);
PAINT GREEN (-2825 4675);
DISPLAY INVISIBLE (-2825 4675);
FORCEPROP 1 LAST PATH I113
J 0
(-3150 4800);
DISPLAY 0.936170 (-3150 4800);
PAINT GREEN (-3150 4800);
DISPLAY INVISIBLE (-3150 4800);
FORCEADD TAP..6
(-3150 4750);
FORCEPROP 3 LASTPIN (-3100 4750) SIG_NAME M_C_MA<15>
J 0
(-3090 4760);
DISPLAY 0.659574 (-3090 4760);
PAINT MONO (-3090 4760);
DISPLAY INVISIBLE (-3090 4760);
FORCEPROP 1 LASTPIN (-3100 4750) BN 15
J 0
(-3150 4760);
DISPLAY 0.617021 (-3150 4760);
PAINT PINK (-3150 4760);
FORCEPROP 2 LAST CDS_LIB mstr_standard
J 2
(-3150 4750);
DISPLAY 0.787234 (-3150 4750);
PAINT MONO (-3150 4750);
DISPLAY INVISIBLE (-3150 4750);
FORCEPROP 1 LAST BODY_TYPE PLUMBING
J 0
(-3150 4700);
DISPLAY 1.234043 (-3150 4700);
PAINT GREEN (-3150 4700);
DISPLAY INVISIBLE (-3150 4700);
FORCEPROP 1 LAST HDL_TAP TRUE
J 0
(-2825 4625);
DISPLAY 1.234043 (-2825 4625);
PAINT GREEN (-2825 4625);
DISPLAY INVISIBLE (-2825 4625);
FORCEPROP 1 LAST PATH I114
J 0
(-3150 4750);
DISPLAY 0.936170 (-3150 4750);
PAINT GREEN (-3150 4750);
DISPLAY INVISIBLE (-3150 4750);
FORCEADD TAP..6
(-3150 4700);
FORCEPROP 3 LASTPIN (-3100 4700) SIG_NAME M_C_MA<14>
J 0
(-3090 4710);
DISPLAY 0.659574 (-3090 4710);
PAINT MONO (-3090 4710);
DISPLAY INVISIBLE (-3090 4710);
FORCEPROP 1 LASTPIN (-3100 4700) BN 14
J 0
(-3150 4710);
DISPLAY 0.617021 (-3150 4710);
PAINT PINK (-3150 4710);
FORCEPROP 2 LAST CDS_LIB mstr_standard
J 2
(-3150 4700);
DISPLAY 0.787234 (-3150 4700);
PAINT MONO (-3150 4700);
DISPLAY INVISIBLE (-3150 4700);
FORCEPROP 1 LAST BODY_TYPE PLUMBING
J 0
(-3150 4650);
DISPLAY 1.234043 (-3150 4650);
PAINT GREEN (-3150 4650);
DISPLAY INVISIBLE (-3150 4650);
FORCEPROP 1 LAST HDL_TAP TRUE
J 0
(-2825 4575);
DISPLAY 1.234043 (-2825 4575);
PAINT GREEN (-2825 4575);
DISPLAY INVISIBLE (-2825 4575);
FORCEPROP 1 LAST PATH I115
J 0
(-3150 4700);
DISPLAY 0.936170 (-3150 4700);
PAINT GREEN (-3150 4700);
DISPLAY INVISIBLE (-3150 4700);
FORCEADD TAP..6
(-3150 4650);
FORCEPROP 3 LASTPIN (-3100 4650) SIG_NAME M_C_MA<13>
J 0
(-3090 4660);
DISPLAY 0.659574 (-3090 4660);
PAINT MONO (-3090 4660);
DISPLAY INVISIBLE (-3090 4660);
FORCEPROP 1 LASTPIN (-3100 4650) BN 13
J 0
(-3150 4660);
DISPLAY 0.617021 (-3150 4660);
PAINT PINK (-3150 4660);
FORCEPROP 2 LAST CDS_LIB mstr_standard
J 2
(-3150 4650);
DISPLAY 0.787234 (-3150 4650);
PAINT MONO (-3150 4650);
DISPLAY INVISIBLE (-3150 4650);
FORCEPROP 1 LAST BODY_TYPE PLUMBING
J 0
(-3150 4600);
DISPLAY 1.234043 (-3150 4600);
PAINT GREEN (-3150 4600);
DISPLAY INVISIBLE (-3150 4600);
FORCEPROP 1 LAST HDL_TAP TRUE
J 0
(-2825 4525);
DISPLAY 1.234043 (-2825 4525);
PAINT GREEN (-2825 4525);
DISPLAY INVISIBLE (-2825 4525);
FORCEPROP 1 LAST PATH I116
J 0
(-3150 4650);
DISPLAY 0.936170 (-3150 4650);
PAINT GREEN (-3150 4650);
DISPLAY INVISIBLE (-3150 4650);
FORCEADD TAP..6
(-3150 4600);
FORCEPROP 3 LASTPIN (-3100 4600) SIG_NAME M_C_MA<12>
J 0
(-3090 4610);
DISPLAY 0.659574 (-3090 4610);
PAINT MONO (-3090 4610);
DISPLAY INVISIBLE (-3090 4610);
FORCEPROP 1 LASTPIN (-3100 4600) BN 12
J 0
(-3150 4610);
DISPLAY 0.617021 (-3150 4610);
PAINT PINK (-3150 4610);
FORCEPROP 2 LAST CDS_LIB mstr_standard
J 2
(-3150 4600);
DISPLAY 0.787234 (-3150 4600);
PAINT MONO (-3150 4600);
DISPLAY INVISIBLE (-3150 4600);
FORCEPROP 1 LAST BODY_TYPE PLUMBING
J 0
(-3150 4550);
DISPLAY 1.234043 (-3150 4550);
PAINT GREEN (-3150 4550);
DISPLAY INVISIBLE (-3150 4550);
FORCEPROP 1 LAST HDL_TAP TRUE
J 0
(-2825 4475);
DISPLAY 1.234043 (-2825 4475);
PAINT GREEN (-2825 4475);
DISPLAY INVISIBLE (-2825 4475);
FORCEPROP 1 LAST PATH I117
J 0
(-3150 4600);
DISPLAY 0.936170 (-3150 4600);
PAINT GREEN (-3150 4600);
DISPLAY INVISIBLE (-3150 4600);
FORCEADD TAP..6
(-3150 4550);
FORCEPROP 3 LASTPIN (-3100 4550) SIG_NAME M_C_MA<11>
J 0
(-3090 4560);
DISPLAY 0.659574 (-3090 4560);
PAINT MONO (-3090 4560);
DISPLAY INVISIBLE (-3090 4560);
FORCEPROP 1 LASTPIN (-3100 4550) BN 11
J 0
(-3150 4560);
DISPLAY 0.617021 (-3150 4560);
PAINT PINK (-3150 4560);
FORCEPROP 2 LAST CDS_LIB mstr_standard
J 2
(-3150 4550);
DISPLAY 0.787234 (-3150 4550);
PAINT MONO (-3150 4550);
DISPLAY INVISIBLE (-3150 4550);
FORCEPROP 1 LAST BODY_TYPE PLUMBING
J 0
(-3150 4500);
DISPLAY 1.234043 (-3150 4500);
PAINT GREEN (-3150 4500);
DISPLAY INVISIBLE (-3150 4500);
FORCEPROP 1 LAST HDL_TAP TRUE
J 0
(-2825 4425);
DISPLAY 1.234043 (-2825 4425);
PAINT GREEN (-2825 4425);
DISPLAY INVISIBLE (-2825 4425);
FORCEPROP 1 LAST PATH I118
J 0
(-3150 4550);
DISPLAY 0.936170 (-3150 4550);
PAINT GREEN (-3150 4550);
DISPLAY INVISIBLE (-3150 4550);
FORCEADD TAP..6
(-3150 4500);
FORCEPROP 3 LASTPIN (-3100 4500) SIG_NAME M_C_MA<10>
J 0
(-3090 4510);
DISPLAY 0.659574 (-3090 4510);
PAINT MONO (-3090 4510);
DISPLAY INVISIBLE (-3090 4510);
FORCEPROP 1 LASTPIN (-3100 4500) BN 10
J 0
(-3150 4510);
DISPLAY 0.617021 (-3150 4510);
PAINT PINK (-3150 4510);
FORCEPROP 2 LAST CDS_LIB mstr_standard
J 2
(-3150 4500);
DISPLAY 0.787234 (-3150 4500);
PAINT MONO (-3150 4500);
DISPLAY INVISIBLE (-3150 4500);
FORCEPROP 1 LAST BODY_TYPE PLUMBING
J 0
(-3150 4450);
DISPLAY 1.234043 (-3150 4450);
PAINT GREEN (-3150 4450);
DISPLAY INVISIBLE (-3150 4450);
FORCEPROP 1 LAST HDL_TAP TRUE
J 0
(-2825 4375);
DISPLAY 1.234043 (-2825 4375);
PAINT GREEN (-2825 4375);
DISPLAY INVISIBLE (-2825 4375);
FORCEPROP 1 LAST PATH I119
J 0
(-3150 4500);
DISPLAY 0.936170 (-3150 4500);
PAINT GREEN (-3150 4500);
DISPLAY INVISIBLE (-3150 4500);
FORCEADD PVTT_ABC..1
(-950 2700);
FORCEPROP 3 LASTPIN (-950 2650) SIG_NAME PVTT_ABC\g
J 0
(-940 2660);
DISPLAY 0.659574 (-940 2660);
PAINT MONO (-940 2660);
DISPLAY INVISIBLE (-940 2660);
FORCEPROP 1 LAST VOLTAGE 0.6V
J 0
(-995 2657);
DISPLAY 0.340426 (-995 2657);
PAINT SKYBLUE (-995 2657);
DISPLAY INVISIBLE (-995 2657);
FORCEPROP 2 LAST BOM_COST MEM
J 0
(-950 2705);
PAINT ORANGE (-950 2705);
DISPLAY INVISIBLE (-950 2705);
FORCEPROP 2 LAST CDS_LIB mstr_symbols
J 0
(-950 2700);
PAINT ORANGE (-950 2700);
DISPLAY INVISIBLE (-950 2700);
FORCEPROP 1 LAST BODY_TYPE PLUMBING
J 0
(-995 2657);
DISPLAY 0.340426 (-995 2657);
PAINT GREEN (-995 2657);
DISPLAY INVISIBLE (-995 2657);
FORCEPROP 1 LAST PATH I12
J 0
(-900 2725);
DISPLAY 0.872340 (-900 2725);
PAINT AQUA (-900 2725);
DISPLAY INVISIBLE (-900 2725);
FORCEPROP 2 LAST ROOM DDR4_CH_B
J 0
(-950 2705);
PAINT ORANGE (-950 2705);
DISPLAY INVISIBLE (-950 2705);
FORCEPROP 1 LAST HDL_POWER PVTT_ABC
J 1
(-950 2750);
DISPLAY 0.872340 (-950 2750);
PAINT GREEN (-950 2750);
DISPLAY INVISIBLE (-950 2750);
FORCEADD TAP..6
(-3150 4450);
FORCEPROP 3 LASTPIN (-3100 4450) SIG_NAME M_C_MA<9>
J 0
(-3090 4460);
DISPLAY 0.659574 (-3090 4460);
PAINT MONO (-3090 4460);
DISPLAY INVISIBLE (-3090 4460);
FORCEPROP 1 LASTPIN (-3100 4450) BN 9
J 0
(-3150 4460);
DISPLAY 0.617021 (-3150 4460);
PAINT PINK (-3150 4460);
FORCEPROP 2 LAST CDS_LIB mstr_standard
J 2
(-3150 4450);
DISPLAY 0.787234 (-3150 4450);
PAINT MONO (-3150 4450);
DISPLAY INVISIBLE (-3150 4450);
FORCEPROP 1 LAST BODY_TYPE PLUMBING
J 0
(-3150 4400);
DISPLAY 1.234043 (-3150 4400);
PAINT GREEN (-3150 4400);
DISPLAY INVISIBLE (-3150 4400);
FORCEPROP 1 LAST HDL_TAP TRUE
J 0
(-2825 4325);
DISPLAY 1.234043 (-2825 4325);
PAINT GREEN (-2825 4325);
DISPLAY INVISIBLE (-2825 4325);
FORCEPROP 1 LAST PATH I120
J 0
(-3150 4450);
DISPLAY 0.936170 (-3150 4450);
PAINT GREEN (-3150 4450);
DISPLAY INVISIBLE (-3150 4450);
FORCEADD TAP..6
(-3150 4400);
FORCEPROP 3 LASTPIN (-3100 4400) SIG_NAME M_C_MA<8>
J 0
(-3090 4410);
DISPLAY 0.659574 (-3090 4410);
PAINT MONO (-3090 4410);
DISPLAY INVISIBLE (-3090 4410);
FORCEPROP 1 LASTPIN (-3100 4400) BN 8
J 0
(-3150 4410);
DISPLAY 0.617021 (-3150 4410);
PAINT PINK (-3150 4410);
FORCEPROP 2 LAST CDS_LIB mstr_standard
J 2
(-3150 4400);
DISPLAY 0.787234 (-3150 4400);
PAINT MONO (-3150 4400);
DISPLAY INVISIBLE (-3150 4400);
FORCEPROP 1 LAST BODY_TYPE PLUMBING
J 0
(-3150 4350);
DISPLAY 1.234043 (-3150 4350);
PAINT GREEN (-3150 4350);
DISPLAY INVISIBLE (-3150 4350);
FORCEPROP 1 LAST HDL_TAP TRUE
J 0
(-2825 4275);
DISPLAY 1.234043 (-2825 4275);
PAINT GREEN (-2825 4275);
DISPLAY INVISIBLE (-2825 4275);
FORCEPROP 1 LAST PATH I121
J 0
(-3150 4400);
DISPLAY 0.936170 (-3150 4400);
PAINT GREEN (-3150 4400);
DISPLAY INVISIBLE (-3150 4400);
FORCEADD TAP..6
(-3150 4350);
FORCEPROP 3 LASTPIN (-3100 4350) SIG_NAME M_C_MA<7>
J 0
(-3090 4360);
DISPLAY 0.659574 (-3090 4360);
PAINT MONO (-3090 4360);
DISPLAY INVISIBLE (-3090 4360);
FORCEPROP 1 LASTPIN (-3100 4350) BN 7
J 0
(-3150 4360);
DISPLAY 0.617021 (-3150 4360);
PAINT PINK (-3150 4360);
FORCEPROP 2 LAST CDS_LIB mstr_standard
J 2
(-3150 4350);
DISPLAY 0.787234 (-3150 4350);
PAINT MONO (-3150 4350);
DISPLAY INVISIBLE (-3150 4350);
FORCEPROP 1 LAST BODY_TYPE PLUMBING
J 0
(-3150 4300);
DISPLAY 1.234043 (-3150 4300);
PAINT GREEN (-3150 4300);
DISPLAY INVISIBLE (-3150 4300);
FORCEPROP 1 LAST HDL_TAP TRUE
J 0
(-2825 4225);
DISPLAY 1.234043 (-2825 4225);
PAINT GREEN (-2825 4225);
DISPLAY INVISIBLE (-2825 4225);
FORCEPROP 1 LAST PATH I122
J 0
(-3150 4350);
DISPLAY 0.936170 (-3150 4350);
PAINT GREEN (-3150 4350);
DISPLAY INVISIBLE (-3150 4350);
FORCEADD TAP..6
(-3150 4300);
FORCEPROP 3 LASTPIN (-3100 4300) SIG_NAME M_C_MA<6>
J 0
(-3090 4310);
DISPLAY 0.659574 (-3090 4310);
PAINT MONO (-3090 4310);
DISPLAY INVISIBLE (-3090 4310);
FORCEPROP 1 LASTPIN (-3100 4300) BN 6
J 0
(-3150 4310);
DISPLAY 0.617021 (-3150 4310);
PAINT PINK (-3150 4310);
FORCEPROP 2 LAST CDS_LIB mstr_standard
J 2
(-3150 4300);
DISPLAY 0.787234 (-3150 4300);
PAINT MONO (-3150 4300);
DISPLAY INVISIBLE (-3150 4300);
FORCEPROP 1 LAST BODY_TYPE PLUMBING
J 0
(-3150 4250);
DISPLAY 1.234043 (-3150 4250);
PAINT GREEN (-3150 4250);
DISPLAY INVISIBLE (-3150 4250);
FORCEPROP 1 LAST HDL_TAP TRUE
J 0
(-2825 4175);
DISPLAY 1.234043 (-2825 4175);
PAINT GREEN (-2825 4175);
DISPLAY INVISIBLE (-2825 4175);
FORCEPROP 1 LAST PATH I123
J 0
(-3150 4300);
DISPLAY 0.936170 (-3150 4300);
PAINT GREEN (-3150 4300);
DISPLAY INVISIBLE (-3150 4300);
FORCEADD TAP..6
(-3150 4250);
FORCEPROP 3 LASTPIN (-3100 4250) SIG_NAME M_C_MA<5>
J 0
(-3090 4260);
DISPLAY 0.659574 (-3090 4260);
PAINT MONO (-3090 4260);
DISPLAY INVISIBLE (-3090 4260);
FORCEPROP 1 LASTPIN (-3100 4250) BN 5
J 0
(-3150 4260);
DISPLAY 0.617021 (-3150 4260);
PAINT PINK (-3150 4260);
FORCEPROP 2 LAST CDS_LIB mstr_standard
J 2
(-3150 4250);
DISPLAY 0.787234 (-3150 4250);
PAINT MONO (-3150 4250);
DISPLAY INVISIBLE (-3150 4250);
FORCEPROP 1 LAST BODY_TYPE PLUMBING
J 0
(-3150 4200);
DISPLAY 1.234043 (-3150 4200);
PAINT GREEN (-3150 4200);
DISPLAY INVISIBLE (-3150 4200);
FORCEPROP 1 LAST HDL_TAP TRUE
J 0
(-2825 4125);
DISPLAY 1.234043 (-2825 4125);
PAINT GREEN (-2825 4125);
DISPLAY INVISIBLE (-2825 4125);
FORCEPROP 1 LAST PATH I124
J 0
(-3150 4250);
DISPLAY 0.936170 (-3150 4250);
PAINT GREEN (-3150 4250);
DISPLAY INVISIBLE (-3150 4250);
FORCEADD TAP..6
(-3150 4200);
FORCEPROP 3 LASTPIN (-3100 4200) SIG_NAME M_C_MA<4>
J 0
(-3090 4210);
DISPLAY 0.659574 (-3090 4210);
PAINT MONO (-3090 4210);
DISPLAY INVISIBLE (-3090 4210);
FORCEPROP 1 LASTPIN (-3100 4200) BN 4
J 0
(-3150 4210);
DISPLAY 0.617021 (-3150 4210);
PAINT PINK (-3150 4210);
FORCEPROP 2 LAST CDS_LIB mstr_standard
J 2
(-3150 4200);
DISPLAY 0.787234 (-3150 4200);
PAINT MONO (-3150 4200);
DISPLAY INVISIBLE (-3150 4200);
FORCEPROP 1 LAST BODY_TYPE PLUMBING
J 0
(-3150 4150);
DISPLAY 1.234043 (-3150 4150);
PAINT GREEN (-3150 4150);
DISPLAY INVISIBLE (-3150 4150);
FORCEPROP 1 LAST HDL_TAP TRUE
J 0
(-2825 4075);
DISPLAY 1.234043 (-2825 4075);
PAINT GREEN (-2825 4075);
DISPLAY INVISIBLE (-2825 4075);
FORCEPROP 1 LAST PATH I125
J 0
(-3150 4200);
DISPLAY 0.936170 (-3150 4200);
PAINT GREEN (-3150 4200);
DISPLAY INVISIBLE (-3150 4200);
FORCEADD TAP..6
(-3150 4150);
FORCEPROP 3 LASTPIN (-3100 4150) SIG_NAME M_C_MA<3>
J 0
(-3090 4160);
DISPLAY 0.659574 (-3090 4160);
PAINT MONO (-3090 4160);
DISPLAY INVISIBLE (-3090 4160);
FORCEPROP 1 LASTPIN (-3100 4150) BN 3
J 0
(-3150 4160);
DISPLAY 0.617021 (-3150 4160);
PAINT PINK (-3150 4160);
FORCEPROP 2 LAST CDS_LIB mstr_standard
J 2
(-3150 4150);
DISPLAY 0.787234 (-3150 4150);
PAINT MONO (-3150 4150);
DISPLAY INVISIBLE (-3150 4150);
FORCEPROP 1 LAST BODY_TYPE PLUMBING
J 0
(-3150 4100);
DISPLAY 1.234043 (-3150 4100);
PAINT GREEN (-3150 4100);
DISPLAY INVISIBLE (-3150 4100);
FORCEPROP 1 LAST HDL_TAP TRUE
J 0
(-2825 4025);
DISPLAY 1.234043 (-2825 4025);
PAINT GREEN (-2825 4025);
DISPLAY INVISIBLE (-2825 4025);
FORCEPROP 1 LAST PATH I126
J 0
(-3150 4150);
DISPLAY 0.936170 (-3150 4150);
PAINT GREEN (-3150 4150);
DISPLAY INVISIBLE (-3150 4150);
FORCEADD OFFPAGE..1
(-3750 4900);
FORCEPROP 2 LAST $XR1 47 
J 0
(-4061 4900);
DISPLAY 0.638298 (-4061 4900);
PAINT MONO (-4061 4900);
FORCEPROP 2 LAST $XR0 25 
J 0
(-3971 4900);
DISPLAY 0.638298 (-3971 4900);
PAINT MONO (-3971 4900);
FORCEPROP 2 LAST CDS_LIB mstr_standard
J 0
(-3750 4900);
DISPLAY 0.787234 (-3750 4900);
PAINT MONO (-3750 4900);
DISPLAY INVISIBLE (-3750 4900);
FORCEPROP 1 LAST OFFPAGE TRUE
J 0
(-3425 4775);
DISPLAY 0.936170 (-3425 4775);
PAINT GREEN (-3425 4775);
DISPLAY INVISIBLE (-3425 4775);
FORCEPROP 1 LAST COMMENT_BODY TRUE
J 0
(-3625 4800);
DISPLAY 0.936170 (-3625 4800);
PAINT GREEN (-3625 4800);
DISPLAY INVISIBLE (-3625 4800);
FORCEPROP 2 LAST PATH I127
J 0
(-3700 4975);
DISPLAY 0.787234 (-3700 4975);
PAINT MONO (-3700 4975);
DISPLAY INVISIBLE (-3700 4975);
FORCEADD TAP..6
(-3150 4100);
FORCEPROP 3 LASTPIN (-3100 4100) SIG_NAME M_C_MA<2>
J 0
(-3090 4110);
DISPLAY 0.659574 (-3090 4110);
PAINT MONO (-3090 4110);
DISPLAY INVISIBLE (-3090 4110);
FORCEPROP 1 LASTPIN (-3100 4100) BN 2
J 0
(-3150 4110);
DISPLAY 0.617021 (-3150 4110);
PAINT PINK (-3150 4110);
FORCEPROP 2 LAST CDS_LIB mstr_standard
J 2
(-3150 4100);
DISPLAY 0.787234 (-3150 4100);
PAINT MONO (-3150 4100);
DISPLAY INVISIBLE (-3150 4100);
FORCEPROP 1 LAST BODY_TYPE PLUMBING
J 0
(-3150 4050);
DISPLAY 1.234043 (-3150 4050);
PAINT GREEN (-3150 4050);
DISPLAY INVISIBLE (-3150 4050);
FORCEPROP 1 LAST HDL_TAP TRUE
J 0
(-2825 3975);
DISPLAY 1.234043 (-2825 3975);
PAINT GREEN (-2825 3975);
DISPLAY INVISIBLE (-2825 3975);
FORCEPROP 1 LAST PATH I128
J 0
(-3150 4100);
DISPLAY 0.936170 (-3150 4100);
PAINT GREEN (-3150 4100);
DISPLAY INVISIBLE (-3150 4100);
FORCEADD TAP..6
(-3150 4050);
FORCEPROP 3 LASTPIN (-3100 4050) SIG_NAME M_C_MA<1>
J 0
(-3090 4060);
DISPLAY 0.659574 (-3090 4060);
PAINT MONO (-3090 4060);
DISPLAY INVISIBLE (-3090 4060);
FORCEPROP 1 LASTPIN (-3100 4050) BN 1
J 0
(-3150 4060);
DISPLAY 0.617021 (-3150 4060);
PAINT PINK (-3150 4060);
FORCEPROP 2 LAST CDS_LIB mstr_standard
J 2
(-3150 4050);
DISPLAY 0.787234 (-3150 4050);
PAINT MONO (-3150 4050);
DISPLAY INVISIBLE (-3150 4050);
FORCEPROP 1 LAST BODY_TYPE PLUMBING
J 0
(-3150 4000);
DISPLAY 1.234043 (-3150 4000);
PAINT GREEN (-3150 4000);
DISPLAY INVISIBLE (-3150 4000);
FORCEPROP 1 LAST HDL_TAP TRUE
J 0
(-2825 3925);
DISPLAY 1.234043 (-2825 3925);
PAINT GREEN (-2825 3925);
DISPLAY INVISIBLE (-2825 3925);
FORCEPROP 1 LAST PATH I129
J 0
(-3150 4050);
DISPLAY 0.936170 (-3150 4050);
PAINT GREEN (-3150 4050);
DISPLAY INVISIBLE (-3150 4050);
FORCEADD PVDDQ_ABC..1
(-1150 2550);
FORCEPROP 3 LASTPIN (-1150 2500) SIG_NAME PVDDQ_ABC\g
J 0
(-1140 2510);
DISPLAY 0.659574 (-1140 2510);
PAINT MONO (-1140 2510);
DISPLAY INVISIBLE (-1140 2510);
FORCEPROP 1 LAST VOLTAGE 1.2V
J 0
(-1195 2507);
DISPLAY 0.340426 (-1195 2507);
PAINT SKYBLUE (-1195 2507);
DISPLAY INVISIBLE (-1195 2507);
FORCEPROP 2 LAST BOM_COST MEM
J 0
(-1150 2555);
PAINT ORANGE (-1150 2555);
DISPLAY INVISIBLE (-1150 2555);
FORCEPROP 2 LAST CDS_LIB mstr_symbols
J 0
(-1150 2550);
PAINT ORANGE (-1150 2550);
DISPLAY INVISIBLE (-1150 2550);
FORCEPROP 1 LAST BODY_TYPE PLUMBING
J 0
(-1195 2507);
DISPLAY 0.340426 (-1195 2507);
PAINT GREEN (-1195 2507);
DISPLAY INVISIBLE (-1195 2507);
FORCEPROP 1 LAST PATH I13
J 0
(-1100 2575);
DISPLAY 0.872340 (-1100 2575);
PAINT AQUA (-1100 2575);
DISPLAY INVISIBLE (-1100 2575);
FORCEPROP 2 LAST ROOM DDR4_CH_B
J 0
(-1150 2555);
PAINT ORANGE (-1150 2555);
DISPLAY INVISIBLE (-1150 2555);
FORCEPROP 1 LAST HDL_POWER PVDDQ_ABC
J 1
(-1150 2600);
DISPLAY 0.872340 (-1150 2600);
PAINT GREEN (-1150 2600);
DISPLAY INVISIBLE (-1150 2600);
FORCEADD TAP..6
(-3150 4000);
FORCEPROP 3 LASTPIN (-3100 4000) SIG_NAME M_C_MA<0>
J 0
(-3090 4010);
DISPLAY 0.659574 (-3090 4010);
PAINT MONO (-3090 4010);
DISPLAY INVISIBLE (-3090 4010);
FORCEPROP 1 LASTPIN (-3100 4000) BN 0
J 0
(-3150 4010);
DISPLAY 0.617021 (-3150 4010);
PAINT PINK (-3150 4010);
FORCEPROP 2 LAST CDS_LIB mstr_standard
J 2
(-3150 4000);
DISPLAY 0.787234 (-3150 4000);
PAINT MONO (-3150 4000);
DISPLAY INVISIBLE (-3150 4000);
FORCEPROP 1 LAST BODY_TYPE PLUMBING
J 0
(-3150 3950);
DISPLAY 1.234043 (-3150 3950);
PAINT GREEN (-3150 3950);
DISPLAY INVISIBLE (-3150 3950);
FORCEPROP 1 LAST HDL_TAP TRUE
J 0
(-2825 3875);
DISPLAY 1.234043 (-2825 3875);
PAINT GREEN (-2825 3875);
DISPLAY INVISIBLE (-2825 3875);
FORCEPROP 1 LAST PATH I130
J 0
(-3150 4000);
DISPLAY 0.936170 (-3150 4000);
PAINT GREEN (-3150 4000);
DISPLAY INVISIBLE (-3150 4000);
FORCEADD TAP..6
(-3150 3900);
FORCEPROP 3 LASTPIN (-3100 3900) SIG_NAME M_C_BA<1>
J 0
(-3090 3910);
DISPLAY 0.659574 (-3090 3910);
PAINT MONO (-3090 3910);
DISPLAY INVISIBLE (-3090 3910);
FORCEPROP 1 LASTPIN (-3100 3900) BN 1
J 0
(-3150 3910);
DISPLAY 0.617021 (-3150 3910);
PAINT PINK (-3150 3910);
FORCEPROP 2 LAST CDS_LIB mstr_standard
J 0
(-3150 3900);
DISPLAY 0.787234 (-3150 3900);
PAINT MONO (-3150 3900);
DISPLAY INVISIBLE (-3150 3900);
FORCEPROP 1 LAST BODY_TYPE PLUMBING
J 0
(-3150 3850);
DISPLAY 1.234043 (-3150 3850);
PAINT GREEN (-3150 3850);
DISPLAY INVISIBLE (-3150 3850);
FORCEPROP 1 LAST HDL_TAP TRUE
J 0
(-2825 3775);
DISPLAY 1.234043 (-2825 3775);
PAINT GREEN (-2825 3775);
DISPLAY INVISIBLE (-2825 3775);
FORCEPROP 1 LAST PATH I131
J 0
(-3150 3900);
DISPLAY 0.936170 (-3150 3900);
PAINT GREEN (-3150 3900);
DISPLAY INVISIBLE (-3150 3900);
FORCEADD TAP..6
(-3150 3850);
FORCEPROP 3 LASTPIN (-3100 3850) SIG_NAME M_C_BA<0>
J 0
(-3090 3860);
DISPLAY 0.659574 (-3090 3860);
PAINT MONO (-3090 3860);
DISPLAY INVISIBLE (-3090 3860);
FORCEPROP 1 LASTPIN (-3100 3850) BN 0
J 0
(-3150 3860);
DISPLAY 0.617021 (-3150 3860);
PAINT PINK (-3150 3860);
FORCEPROP 2 LAST CDS_LIB mstr_standard
J 0
(-3150 3850);
DISPLAY 0.787234 (-3150 3850);
PAINT MONO (-3150 3850);
DISPLAY INVISIBLE (-3150 3850);
FORCEPROP 1 LAST BODY_TYPE PLUMBING
J 0
(-3150 3800);
DISPLAY 1.234043 (-3150 3800);
PAINT GREEN (-3150 3800);
DISPLAY INVISIBLE (-3150 3800);
FORCEPROP 1 LAST HDL_TAP TRUE
J 0
(-2825 3725);
DISPLAY 1.234043 (-2825 3725);
PAINT GREEN (-2825 3725);
DISPLAY INVISIBLE (-2825 3725);
FORCEPROP 1 LAST PATH I132
J 0
(-3150 3850);
DISPLAY 0.936170 (-3150 3850);
PAINT GREEN (-3150 3850);
DISPLAY INVISIBLE (-3150 3850);
FORCEADD TAP..6
(-3150 3750);
FORCEPROP 3 LASTPIN (-3100 3750) SIG_NAME M_C_BG<0>
J 0
(-3090 3760);
DISPLAY 0.659574 (-3090 3760);
PAINT MONO (-3090 3760);
DISPLAY INVISIBLE (-3090 3760);
FORCEPROP 1 LASTPIN (-3100 3750) BN 0
J 0
(-3150 3760);
DISPLAY 0.617021 (-3150 3760);
PAINT PINK (-3150 3760);
FORCEPROP 2 LAST CDS_LIB mstr_standard
J 0
(-3150 3750);
DISPLAY 0.787234 (-3150 3750);
PAINT MONO (-3150 3750);
DISPLAY INVISIBLE (-3150 3750);
FORCEPROP 1 LAST BODY_TYPE PLUMBING
J 0
(-3150 3700);
DISPLAY 1.234043 (-3150 3700);
PAINT GREEN (-3150 3700);
DISPLAY INVISIBLE (-3150 3700);
FORCEPROP 1 LAST HDL_TAP TRUE
J 0
(-2825 3625);
DISPLAY 1.234043 (-2825 3625);
PAINT GREEN (-2825 3625);
DISPLAY INVISIBLE (-2825 3625);
FORCEPROP 1 LAST PATH I133
J 0
(-3150 3750);
DISPLAY 0.936170 (-3150 3750);
PAINT GREEN (-3150 3750);
DISPLAY INVISIBLE (-3150 3750);
FORCEADD TAP..6
(-3150 3800);
FORCEPROP 3 LASTPIN (-3100 3800) SIG_NAME M_C_BG<1>
J 0
(-3090 3810);
DISPLAY 0.659574 (-3090 3810);
PAINT MONO (-3090 3810);
DISPLAY INVISIBLE (-3090 3810);
FORCEPROP 1 LASTPIN (-3100 3800) BN 1
J 0
(-3150 3810);
DISPLAY 0.617021 (-3150 3810);
PAINT PINK (-3150 3810);
FORCEPROP 2 LAST CDS_LIB mstr_standard
J 0
(-3150 3800);
DISPLAY 0.787234 (-3150 3800);
PAINT MONO (-3150 3800);
DISPLAY INVISIBLE (-3150 3800);
FORCEPROP 1 LAST BODY_TYPE PLUMBING
J 0
(-3150 3750);
DISPLAY 1.234043 (-3150 3750);
PAINT GREEN (-3150 3750);
DISPLAY INVISIBLE (-3150 3750);
FORCEPROP 1 LAST HDL_TAP TRUE
J 0
(-2825 3675);
DISPLAY 1.234043 (-2825 3675);
PAINT GREEN (-2825 3675);
DISPLAY INVISIBLE (-2825 3675);
FORCEPROP 1 LAST PATH I134
J 0
(-3150 3800);
DISPLAY 0.936170 (-3150 3800);
PAINT GREEN (-3150 3800);
DISPLAY INVISIBLE (-3150 3800);
FORCEADD OFFPAGE..1
(-3750 3450);
FORCEPROP 2 LAST $XR1 47 
J 0
(-4061 3450);
DISPLAY 0.638298 (-4061 3450);
PAINT MONO (-4061 3450);
FORCEPROP 2 LAST $XR0 25 
J 0
(-3971 3450);
DISPLAY 0.638298 (-3971 3450);
PAINT MONO (-3971 3450);
FORCEPROP 2 LAST CDS_LIB mstr_standard
J 0
(-3750 3450);
DISPLAY 0.787234 (-3750 3450);
PAINT MONO (-3750 3450);
DISPLAY INVISIBLE (-3750 3450);
FORCEPROP 1 LAST OFFPAGE TRUE
J 0
(-3425 3325);
DISPLAY 0.936170 (-3425 3325);
PAINT GREEN (-3425 3325);
DISPLAY INVISIBLE (-3425 3325);
FORCEPROP 1 LAST COMMENT_BODY TRUE
J 0
(-3625 3350);
DISPLAY 0.936170 (-3625 3350);
PAINT GREEN (-3625 3350);
DISPLAY INVISIBLE (-3625 3350);
FORCEPROP 2 LAST PATH I135
J 0
(-3700 3525);
DISPLAY 0.787234 (-3700 3525);
PAINT MONO (-3700 3525);
DISPLAY INVISIBLE (-3700 3525);
FORCEADD OFFPAGE..1
(-3750 3950);
FORCEPROP 2 LAST $XR1 47 
J 0
(-4061 3950);
DISPLAY 0.638298 (-4061 3950);
PAINT MONO (-4061 3950);
FORCEPROP 2 LAST $XR0 25 
J 0
(-3971 3950);
DISPLAY 0.638298 (-3971 3950);
PAINT MONO (-3971 3950);
FORCEPROP 2 LAST CDS_LIB mstr_standard
J 0
(-3750 3950);
DISPLAY 0.787234 (-3750 3950);
PAINT MONO (-3750 3950);
DISPLAY INVISIBLE (-3750 3950);
FORCEPROP 1 LAST OFFPAGE TRUE
J 0
(-3425 3825);
DISPLAY 0.936170 (-3425 3825);
PAINT GREEN (-3425 3825);
DISPLAY INVISIBLE (-3425 3825);
FORCEPROP 1 LAST COMMENT_BODY TRUE
J 0
(-3625 3850);
DISPLAY 0.936170 (-3625 3850);
PAINT GREEN (-3625 3850);
DISPLAY INVISIBLE (-3625 3850);
FORCEPROP 2 LAST PATH I136
J 0
(-3700 4025);
DISPLAY 0.787234 (-3700 4025);
PAINT MONO (-3700 4025);
DISPLAY INVISIBLE (-3700 4025);
FORCEADD OFFPAGE..1
(-3750 3850);
FORCEPROP 2 LAST $XR1 47 
J 0
(-4061 3850);
DISPLAY 0.638298 (-4061 3850);
PAINT MONO (-4061 3850);
FORCEPROP 2 LAST $XR0 25 
J 0
(-3971 3850);
DISPLAY 0.638298 (-3971 3850);
PAINT MONO (-3971 3850);
FORCEPROP 2 LAST CDS_LIB mstr_standard
J 0
(-3750 3850);
DISPLAY 0.787234 (-3750 3850);
PAINT MONO (-3750 3850);
DISPLAY INVISIBLE (-3750 3850);
FORCEPROP 1 LAST OFFPAGE TRUE
J 0
(-3425 3725);
DISPLAY 0.936170 (-3425 3725);
PAINT GREEN (-3425 3725);
DISPLAY INVISIBLE (-3425 3725);
FORCEPROP 1 LAST COMMENT_BODY TRUE
J 0
(-3625 3750);
DISPLAY 0.936170 (-3625 3750);
PAINT GREEN (-3625 3750);
DISPLAY INVISIBLE (-3625 3750);
FORCEPROP 2 LAST PATH I137
J 0
(-3700 3925);
DISPLAY 0.787234 (-3700 3925);
PAINT MONO (-3700 3925);
DISPLAY INVISIBLE (-3700 3925);
FORCEADD TAP..6
(-3150 2800);
FORCEPROP 3 LASTPIN (-3100 2800) SIG_NAME M_C_ECC<7>
J 0
(-3090 2810);
DISPLAY 0.659574 (-3090 2810);
PAINT MONO (-3090 2810);
DISPLAY INVISIBLE (-3090 2810);
FORCEPROP 1 LASTPIN (-3100 2800) BN 7
J 0
(-3150 2810);
DISPLAY 0.617021 (-3150 2810);
PAINT PINK (-3150 2810);
FORCEPROP 2 LAST CDS_LIB mstr_standard
J 0
(-3150 2800);
DISPLAY 0.787234 (-3150 2800);
PAINT MONO (-3150 2800);
DISPLAY INVISIBLE (-3150 2800);
FORCEPROP 1 LAST BODY_TYPE PLUMBING
J 0
(-3150 2750);
DISPLAY 1.234043 (-3150 2750);
PAINT GREEN (-3150 2750);
DISPLAY INVISIBLE (-3150 2750);
FORCEPROP 1 LAST HDL_TAP TRUE
J 0
(-2825 2675);
DISPLAY 1.234043 (-2825 2675);
PAINT GREEN (-2825 2675);
DISPLAY INVISIBLE (-2825 2675);
FORCEPROP 1 LAST PATH I138
J 0
(-3150 2800);
DISPLAY 0.936170 (-3150 2800);
PAINT GREEN (-3150 2800);
DISPLAY INVISIBLE (-3150 2800);
FORCEADD TAP..6
(-3150 2750);
FORCEPROP 3 LASTPIN (-3100 2750) SIG_NAME M_C_ECC<6>
J 0
(-3090 2760);
DISPLAY 0.659574 (-3090 2760);
PAINT MONO (-3090 2760);
DISPLAY INVISIBLE (-3090 2760);
FORCEPROP 1 LASTPIN (-3100 2750) BN 6
J 0
(-3150 2760);
DISPLAY 0.617021 (-3150 2760);
PAINT PINK (-3150 2760);
FORCEPROP 2 LAST CDS_LIB mstr_standard
J 0
(-3150 2750);
DISPLAY 0.787234 (-3150 2750);
PAINT MONO (-3150 2750);
DISPLAY INVISIBLE (-3150 2750);
FORCEPROP 1 LAST BODY_TYPE PLUMBING
J 0
(-3150 2700);
DISPLAY 1.234043 (-3150 2700);
PAINT GREEN (-3150 2700);
DISPLAY INVISIBLE (-3150 2700);
FORCEPROP 1 LAST HDL_TAP TRUE
J 0
(-2825 2625);
DISPLAY 1.234043 (-2825 2625);
PAINT GREEN (-2825 2625);
DISPLAY INVISIBLE (-2825 2625);
FORCEPROP 1 LAST PATH I139
J 0
(-3150 2750);
DISPLAY 0.936170 (-3150 2750);
PAINT GREEN (-3150 2750);
DISPLAY INVISIBLE (-3150 2750);
FORCEADD TAP..6
R 2
(900 4600);
FORCEPROP 3 LASTPIN (850 4600) SIG_NAME M_C_DQS_DN<12>
J 0
(860 4610);
DISPLAY 0.659574 (860 4610);
PAINT MONO (860 4610);
DISPLAY INVISIBLE (860 4610);
FORCEPROP 1 LASTPIN (850 4600) BN 12
J 2
(900 4610);
DISPLAY 0.617021 (900 4610);
PAINT PINK (900 4610);
FORCEPROP 2 LAST CDS_LIB mstr_standard
J 0
(900 4600);
DISPLAY 0.787234 (900 4600);
PAINT MONO (900 4600);
DISPLAY INVISIBLE (900 4600);
FORCEPROP 1 LAST BODY_TYPE PLUMBING
J 2
(900 4550);
DISPLAY 1.234043 (900 4550);
PAINT GREEN (900 4550);
DISPLAY INVISIBLE (900 4550);
FORCEPROP 1 LAST HDL_TAP TRUE
J 2
(575 4475);
DISPLAY 1.234043 (575 4475);
PAINT GREEN (575 4475);
DISPLAY INVISIBLE (575 4475);
FORCEPROP 1 LAST PATH I14
J 2
(900 4600);
DISPLAY 0.936170 (900 4600);
PAINT GREEN (900 4600);
DISPLAY INVISIBLE (900 4600);
FORCEADD TAP..6
(-3150 2700);
FORCEPROP 3 LASTPIN (-3100 2700) SIG_NAME M_C_ECC<5>
J 0
(-3090 2710);
DISPLAY 0.659574 (-3090 2710);
PAINT MONO (-3090 2710);
DISPLAY INVISIBLE (-3090 2710);
FORCEPROP 1 LASTPIN (-3100 2700) BN 5
J 0
(-3150 2710);
DISPLAY 0.617021 (-3150 2710);
PAINT PINK (-3150 2710);
FORCEPROP 2 LAST CDS_LIB mstr_standard
J 0
(-3150 2700);
DISPLAY 0.787234 (-3150 2700);
PAINT MONO (-3150 2700);
DISPLAY INVISIBLE (-3150 2700);
FORCEPROP 1 LAST BODY_TYPE PLUMBING
J 0
(-3150 2650);
DISPLAY 1.234043 (-3150 2650);
PAINT GREEN (-3150 2650);
DISPLAY INVISIBLE (-3150 2650);
FORCEPROP 1 LAST HDL_TAP TRUE
J 0
(-2825 2575);
DISPLAY 1.234043 (-2825 2575);
PAINT GREEN (-2825 2575);
DISPLAY INVISIBLE (-2825 2575);
FORCEPROP 1 LAST PATH I140
J 0
(-3150 2700);
DISPLAY 0.936170 (-3150 2700);
PAINT GREEN (-3150 2700);
DISPLAY INVISIBLE (-3150 2700);
FORCEADD TAP..6
(-3150 2650);
FORCEPROP 3 LASTPIN (-3100 2650) SIG_NAME M_C_ECC<4>
J 0
(-3090 2660);
DISPLAY 0.659574 (-3090 2660);
PAINT MONO (-3090 2660);
DISPLAY INVISIBLE (-3090 2660);
FORCEPROP 1 LASTPIN (-3100 2650) BN 4
J 0
(-3150 2660);
DISPLAY 0.617021 (-3150 2660);
PAINT PINK (-3150 2660);
FORCEPROP 2 LAST CDS_LIB mstr_standard
J 0
(-3150 2650);
DISPLAY 0.787234 (-3150 2650);
PAINT MONO (-3150 2650);
DISPLAY INVISIBLE (-3150 2650);
FORCEPROP 1 LAST BODY_TYPE PLUMBING
J 0
(-3150 2600);
DISPLAY 1.234043 (-3150 2600);
PAINT GREEN (-3150 2600);
DISPLAY INVISIBLE (-3150 2600);
FORCEPROP 1 LAST HDL_TAP TRUE
J 0
(-2825 2525);
DISPLAY 1.234043 (-2825 2525);
PAINT GREEN (-2825 2525);
DISPLAY INVISIBLE (-2825 2525);
FORCEPROP 1 LAST PATH I141
J 0
(-3150 2650);
DISPLAY 0.936170 (-3150 2650);
PAINT GREEN (-3150 2650);
DISPLAY INVISIBLE (-3150 2650);
FORCEADD TAP..6
(-3150 2600);
FORCEPROP 3 LASTPIN (-3100 2600) SIG_NAME M_C_ECC<3>
J 0
(-3090 2610);
DISPLAY 0.659574 (-3090 2610);
PAINT MONO (-3090 2610);
DISPLAY INVISIBLE (-3090 2610);
FORCEPROP 1 LASTPIN (-3100 2600) BN 3
J 0
(-3150 2610);
DISPLAY 0.617021 (-3150 2610);
PAINT PINK (-3150 2610);
FORCEPROP 2 LAST CDS_LIB mstr_standard
J 0
(-3150 2600);
DISPLAY 0.787234 (-3150 2600);
PAINT MONO (-3150 2600);
DISPLAY INVISIBLE (-3150 2600);
FORCEPROP 1 LAST BODY_TYPE PLUMBING
J 0
(-3150 2550);
DISPLAY 1.234043 (-3150 2550);
PAINT GREEN (-3150 2550);
DISPLAY INVISIBLE (-3150 2550);
FORCEPROP 1 LAST HDL_TAP TRUE
J 0
(-2825 2475);
DISPLAY 1.234043 (-2825 2475);
PAINT GREEN (-2825 2475);
DISPLAY INVISIBLE (-2825 2475);
FORCEPROP 1 LAST PATH I142
J 0
(-3150 2600);
DISPLAY 0.936170 (-3150 2600);
PAINT GREEN (-3150 2600);
DISPLAY INVISIBLE (-3150 2600);
FORCEADD TAP..6
(-3150 2550);
FORCEPROP 3 LASTPIN (-3100 2550) SIG_NAME M_C_ECC<2>
J 0
(-3090 2560);
DISPLAY 0.659574 (-3090 2560);
PAINT MONO (-3090 2560);
DISPLAY INVISIBLE (-3090 2560);
FORCEPROP 1 LASTPIN (-3100 2550) BN 2
J 0
(-3150 2560);
DISPLAY 0.617021 (-3150 2560);
PAINT PINK (-3150 2560);
FORCEPROP 2 LAST CDS_LIB mstr_standard
J 0
(-3150 2550);
DISPLAY 0.787234 (-3150 2550);
PAINT MONO (-3150 2550);
DISPLAY INVISIBLE (-3150 2550);
FORCEPROP 1 LAST BODY_TYPE PLUMBING
J 0
(-3150 2500);
DISPLAY 1.234043 (-3150 2500);
PAINT GREEN (-3150 2500);
DISPLAY INVISIBLE (-3150 2500);
FORCEPROP 1 LAST HDL_TAP TRUE
J 0
(-2825 2425);
DISPLAY 1.234043 (-2825 2425);
PAINT GREEN (-2825 2425);
DISPLAY INVISIBLE (-2825 2425);
FORCEPROP 1 LAST PATH I143
J 0
(-3150 2550);
DISPLAY 0.936170 (-3150 2550);
PAINT GREEN (-3150 2550);
DISPLAY INVISIBLE (-3150 2550);
FORCEADD TAP..6
(-3150 2500);
FORCEPROP 3 LASTPIN (-3100 2500) SIG_NAME M_C_ECC<1>
J 0
(-3090 2510);
DISPLAY 0.659574 (-3090 2510);
PAINT MONO (-3090 2510);
DISPLAY INVISIBLE (-3090 2510);
FORCEPROP 1 LASTPIN (-3100 2500) BN 1
J 0
(-3150 2510);
DISPLAY 0.617021 (-3150 2510);
PAINT PINK (-3150 2510);
FORCEPROP 2 LAST CDS_LIB mstr_standard
J 0
(-3150 2500);
DISPLAY 0.787234 (-3150 2500);
PAINT MONO (-3150 2500);
DISPLAY INVISIBLE (-3150 2500);
FORCEPROP 1 LAST BODY_TYPE PLUMBING
J 0
(-3150 2450);
DISPLAY 1.234043 (-3150 2450);
PAINT GREEN (-3150 2450);
DISPLAY INVISIBLE (-3150 2450);
FORCEPROP 1 LAST HDL_TAP TRUE
J 0
(-2825 2375);
DISPLAY 1.234043 (-2825 2375);
PAINT GREEN (-2825 2375);
DISPLAY INVISIBLE (-2825 2375);
FORCEPROP 1 LAST PATH I144
J 0
(-3150 2500);
DISPLAY 0.936170 (-3150 2500);
PAINT GREEN (-3150 2500);
DISPLAY INVISIBLE (-3150 2500);
FORCEADD TAP..6
(-3150 2450);
FORCEPROP 3 LASTPIN (-3100 2450) SIG_NAME M_C_ECC<0>
J 0
(-3090 2460);
DISPLAY 0.659574 (-3090 2460);
PAINT MONO (-3090 2460);
DISPLAY INVISIBLE (-3090 2460);
FORCEPROP 1 LASTPIN (-3100 2450) BN 0
J 0
(-3150 2460);
DISPLAY 0.617021 (-3150 2460);
PAINT PINK (-3150 2460);
FORCEPROP 2 LAST CDS_LIB mstr_standard
J 0
(-3150 2450);
DISPLAY 0.787234 (-3150 2450);
PAINT MONO (-3150 2450);
DISPLAY INVISIBLE (-3150 2450);
FORCEPROP 1 LAST BODY_TYPE PLUMBING
J 0
(-3150 2400);
DISPLAY 1.234043 (-3150 2400);
PAINT GREEN (-3150 2400);
DISPLAY INVISIBLE (-3150 2400);
FORCEPROP 1 LAST HDL_TAP TRUE
J 0
(-2825 2325);
DISPLAY 1.234043 (-2825 2325);
PAINT GREEN (-2825 2325);
DISPLAY INVISIBLE (-2825 2325);
FORCEPROP 1 LAST PATH I145
J 0
(-3150 2450);
DISPLAY 0.936170 (-3150 2450);
PAINT GREEN (-3150 2450);
DISPLAY INVISIBLE (-3150 2450);
FORCEADD OFFPAGE..1
(-3750 2800);
FORCEPROP 2 LAST $XR1 47 
J 0
(-4091 2800);
DISPLAY 0.638298 (-4091 2800);
PAINT MONO (-4091 2800);
FORCEPROP 2 LAST $XR0 25 
J 0
(-4001 2800);
DISPLAY 0.638298 (-4001 2800);
PAINT MONO (-4001 2800);
FORCEPROP 2 LAST CDS_LIB mstr_standard
J 0
(-3750 2800);
DISPLAY 0.787234 (-3750 2800);
PAINT MONO (-3750 2800);
DISPLAY INVISIBLE (-3750 2800);
FORCEPROP 1 LAST OFFPAGE TRUE
J 0
(-3425 2675);
DISPLAY 0.936170 (-3425 2675);
PAINT GREEN (-3425 2675);
DISPLAY INVISIBLE (-3425 2675);
FORCEPROP 1 LAST COMMENT_BODY TRUE
J 0
(-3625 2700);
DISPLAY 0.936170 (-3625 2700);
PAINT GREEN (-3625 2700);
DISPLAY INVISIBLE (-3625 2700);
FORCEPROP 2 LAST PATH I146
J 0
(-3700 2875);
DISPLAY 0.787234 (-3700 2875);
PAINT MONO (-3700 2875);
DISPLAY INVISIBLE (-3700 2875);
FORCEADD OFFPAGE..1
(-3750 2750);
FORCEPROP 2 LAST $XR5 47 
J 0
(-4421 2750);
DISPLAY 0.638298 (-4421 2750);
PAINT MONO (-4421 2750);
FORCEPROP 2 LAST $XR4 46 
J 0
(-4331 2750);
DISPLAY 0.638298 (-4331 2750);
PAINT MONO (-4331 2750);
FORCEPROP 2 LAST $XR3 45 
J 0
(-4241 2750);
DISPLAY 0.638298 (-4241 2750);
PAINT MONO (-4241 2750);
FORCEPROP 2 LAST $XR2 44 
J 0
(-4151 2750);
DISPLAY 0.638298 (-4151 2750);
PAINT MONO (-4151 2750);
FORCEPROP 2 LAST $XR1 43 
J 0
(-4061 2750);
DISPLAY 0.638298 (-4061 2750);
PAINT MONO (-4061 2750);
FORCEPROP 2 LAST $XR0 21 
J 0
(-3971 2750);
DISPLAY 0.638298 (-3971 2750);
PAINT MONO (-3971 2750);
FORCEPROP 2 LAST CDS_LIB mstr_standard
J 0
(-3750 2750);
DISPLAY 0.787234 (-3750 2750);
PAINT MONO (-3750 2750);
DISPLAY INVISIBLE (-3750 2750);
FORCEPROP 1 LAST OFFPAGE TRUE
J 0
(-3425 2625);
DISPLAY 0.936170 (-3425 2625);
PAINT GREEN (-3425 2625);
DISPLAY INVISIBLE (-3425 2625);
FORCEPROP 1 LAST COMMENT_BODY TRUE
J 0
(-3625 2650);
DISPLAY 0.936170 (-3625 2650);
PAINT GREEN (-3625 2650);
DISPLAY INVISIBLE (-3625 2650);
FORCEPROP 2 LAST PATH I147
J 0
(-3700 2825);
DISPLAY 0.787234 (-3700 2825);
PAINT MONO (-3700 2825);
DISPLAY INVISIBLE (-3700 2825);
FORCEADD OFFPAGE..5
(-3975 2200);
FORCEPROP 2 LAST $XR1 25 
J 0
(-4319 2200);
DISPLAY 0.638298 (-4319 2200);
PAINT MONO (-4319 2200);
FORCEPROP 2 LAST $XR0 47 
J 0
(-4229 2200);
DISPLAY 0.638298 (-4229 2200);
PAINT MONO (-4229 2200);
FORCEPROP 2 LAST CDS_LIB mstr_standard
J 0
(-3975 2200);
DISPLAY 0.787234 (-3975 2200);
PAINT MONO (-3975 2200);
DISPLAY INVISIBLE (-3975 2200);
FORCEPROP 1 LAST OFFPAGE TRUE
J 0
(-3650 2075);
DISPLAY 1.404255 (-3650 2075);
PAINT GREEN (-3650 2075);
DISPLAY INVISIBLE (-3650 2075);
FORCEPROP 1 LAST COMMENT_BODY TRUE
J 0
(-3875 2125);
DISPLAY 1.404255 (-3875 2125);
PAINT GREEN (-3875 2125);
DISPLAY INVISIBLE (-3875 2125);
FORCEPROP 2 LAST PATH I148
J 0
(-3925 2275);
DISPLAY 0.787234 (-3925 2275);
PAINT MONO (-3925 2275);
DISPLAY INVISIBLE (-3925 2275);
FORCEADD OFFPAGE..1
(-3950 2150);
FORCEPROP 2 LAST $XR1 47 
J 0
(-4291 2150);
DISPLAY 0.638298 (-4291 2150);
PAINT MONO (-4291 2150);
FORCEPROP 2 LAST $XR0 25 
J 0
(-4201 2150);
DISPLAY 0.638298 (-4201 2150);
PAINT MONO (-4201 2150);
FORCEPROP 2 LAST CDS_LIB mstr_standard
J 0
(-3950 2150);
DISPLAY 0.787234 (-3950 2150);
PAINT MONO (-3950 2150);
DISPLAY INVISIBLE (-3950 2150);
FORCEPROP 1 LAST OFFPAGE TRUE
J 0
(-3625 2025);
DISPLAY 0.936170 (-3625 2025);
PAINT GREEN (-3625 2025);
DISPLAY INVISIBLE (-3625 2025);
FORCEPROP 1 LAST COMMENT_BODY TRUE
J 0
(-3825 2050);
DISPLAY 0.936170 (-3825 2050);
PAINT GREEN (-3825 2050);
DISPLAY INVISIBLE (-3825 2050);
FORCEPROP 2 LAST PATH I149
J 0
(-3900 2225);
DISPLAY 0.787234 (-3900 2225);
PAINT MONO (-3900 2225);
DISPLAY INVISIBLE (-3900 2225);
FORCEADD TAP..6
R 2
(900 4700);
FORCEPROP 3 LASTPIN (850 4700) SIG_NAME M_C_DQS_DN<13>
J 0
(860 4710);
DISPLAY 0.659574 (860 4710);
PAINT MONO (860 4710);
DISPLAY INVISIBLE (860 4710);
FORCEPROP 1 LASTPIN (850 4700) BN 13
J 2
(900 4710);
DISPLAY 0.617021 (900 4710);
PAINT PINK (900 4710);
FORCEPROP 2 LAST CDS_LIB mstr_standard
J 0
(900 4700);
DISPLAY 0.787234 (900 4700);
PAINT MONO (900 4700);
DISPLAY INVISIBLE (900 4700);
FORCEPROP 1 LAST BODY_TYPE PLUMBING
J 2
(900 4650);
DISPLAY 1.234043 (900 4650);
PAINT GREEN (900 4650);
DISPLAY INVISIBLE (900 4650);
FORCEPROP 1 LAST HDL_TAP TRUE
J 2
(575 4575);
DISPLAY 1.234043 (575 4575);
PAINT GREEN (575 4575);
DISPLAY INVISIBLE (575 4575);
FORCEPROP 1 LAST PATH I15
J 2
(900 4700);
DISPLAY 0.936170 (900 4700);
PAINT GREEN (900 4700);
DISPLAY INVISIBLE (900 4700);
FORCEADD OFFPAGE..6
(-3750 2850);
FORCEPROP 2 LAST $XR1 47 
J 0
(-4119 2850);
DISPLAY 0.638298 (-4119 2850);
PAINT MONO (-4119 2850);
FORCEPROP 2 LAST $XR0 25 
J 0
(-4029 2850);
DISPLAY 0.638298 (-4029 2850);
PAINT MONO (-4029 2850);
FORCEPROP 2 LAST CDS_LIB mstr_standard
J 0
(-3750 2850);
DISPLAY 0.787234 (-3750 2850);
PAINT MONO (-3750 2850);
DISPLAY INVISIBLE (-3750 2850);
FORCEPROP 1 LAST OFFPAGE TRUE
J 0
(-3425 2725);
DISPLAY 0.936170 (-3425 2725);
PAINT GREEN (-3425 2725);
DISPLAY INVISIBLE (-3425 2725);
FORCEPROP 1 LAST COMMENT_BODY TRUE
J 0
(-3650 2775);
DISPLAY 0.936170 (-3650 2775);
PAINT GREEN (-3650 2775);
DISPLAY INVISIBLE (-3650 2775);
FORCEPROP 2 LAST PATH I150
J 0
(-3700 2925);
DISPLAY 0.787234 (-3700 2925);
PAINT MONO (-3700 2925);
DISPLAY INVISIBLE (-3700 2925);
FORCEADD OFFPAGE..1
(-4800 1700);
FORCEPROP 2 LAST $XR1 47 
J 0
(-5141 1700);
DISPLAY 0.638298 (-5141 1700);
PAINT MONO (-5141 1700);
FORCEPROP 2 LAST $XR0 98 
J 0
(-5051 1700);
DISPLAY 0.638298 (-5051 1700);
PAINT MONO (-5051 1700);
FORCEPROP 2 LAST CDS_LIB mstr_standard
J 0
(-4800 1700);
DISPLAY 0.787234 (-4800 1700);
PAINT MONO (-4800 1700);
DISPLAY INVISIBLE (-4800 1700);
FORCEPROP 1 LAST OFFPAGE TRUE
J 0
(-4475 1575);
DISPLAY 0.936170 (-4475 1575);
PAINT GREEN (-4475 1575);
DISPLAY INVISIBLE (-4475 1575);
FORCEPROP 1 LAST COMMENT_BODY TRUE
J 0
(-4675 1600);
DISPLAY 0.936170 (-4675 1600);
PAINT GREEN (-4675 1600);
DISPLAY INVISIBLE (-4675 1600);
FORCEPROP 2 LAST PATH I151
J 0
(-4750 1775);
DISPLAY 0.787234 (-4750 1775);
PAINT MONO (-4750 1775);
DISPLAY INVISIBLE (-4750 1775);
FORCEADD TAP..6
(-3150 3100);
FORCEPROP 3 LASTPIN (-3100 3100) SIG_NAME M_C_CKE<3>
J 0
(-3090 3110);
DISPLAY 0.659574 (-3090 3110);
PAINT MONO (-3090 3110);
DISPLAY INVISIBLE (-3090 3110);
FORCEPROP 1 LASTPIN (-3100 3100) BN 3
J 0
(-3150 3110);
DISPLAY 0.617021 (-3150 3110);
PAINT PINK (-3150 3110);
FORCEPROP 2 LAST CDS_LIB mstr_standard
J 0
(-3150 3100);
DISPLAY 0.787234 (-3150 3100);
PAINT MONO (-3150 3100);
DISPLAY INVISIBLE (-3150 3100);
FORCEPROP 1 LAST BODY_TYPE PLUMBING
J 0
(-3150 3050);
DISPLAY 1.234043 (-3150 3050);
PAINT GREEN (-3150 3050);
DISPLAY INVISIBLE (-3150 3050);
FORCEPROP 1 LAST HDL_TAP TRUE
J 0
(-2825 2975);
DISPLAY 1.234043 (-2825 2975);
PAINT GREEN (-2825 2975);
DISPLAY INVISIBLE (-2825 2975);
FORCEPROP 1 LAST PATH I152
J 0
(-3150 3100);
DISPLAY 0.936170 (-3150 3100);
PAINT GREEN (-3150 3100);
DISPLAY INVISIBLE (-3150 3100);
FORCEADD OFFPAGE..1
(-3750 3150);
FORCEPROP 2 LAST $XR1 47 
J 0
(-4061 3150);
DISPLAY 0.638298 (-4061 3150);
PAINT MONO (-4061 3150);
FORCEPROP 2 LAST $XR0 25 
J 0
(-3971 3150);
DISPLAY 0.638298 (-3971 3150);
PAINT MONO (-3971 3150);
FORCEPROP 2 LAST CDS_LIB mstr_standard
J 0
(-3750 3150);
DISPLAY 0.787234 (-3750 3150);
PAINT MONO (-3750 3150);
DISPLAY INVISIBLE (-3750 3150);
FORCEPROP 1 LAST OFFPAGE TRUE
J 0
(-3425 3025);
DISPLAY 0.936170 (-3425 3025);
PAINT GREEN (-3425 3025);
DISPLAY INVISIBLE (-3425 3025);
FORCEPROP 1 LAST COMMENT_BODY TRUE
J 0
(-3625 3050);
DISPLAY 0.936170 (-3625 3050);
PAINT GREEN (-3625 3050);
DISPLAY INVISIBLE (-3625 3050);
FORCEPROP 2 LAST PATH I153
J 0
(-3700 3225);
DISPLAY 0.787234 (-3700 3225);
PAINT MONO (-3700 3225);
DISPLAY INVISIBLE (-3700 3225);
FORCEADD TAP..6
(-3150 3050);
FORCEPROP 3 LASTPIN (-3100 3050) SIG_NAME M_C_CKE<2>
J 0
(-3090 3060);
DISPLAY 0.659574 (-3090 3060);
PAINT MONO (-3090 3060);
DISPLAY INVISIBLE (-3090 3060);
FORCEPROP 1 LASTPIN (-3100 3050) BN 2
J 0
(-3150 3060);
DISPLAY 0.617021 (-3150 3060);
PAINT PINK (-3150 3060);
FORCEPROP 2 LAST CDS_LIB mstr_standard
J 0
(-3150 3050);
DISPLAY 0.787234 (-3150 3050);
PAINT MONO (-3150 3050);
DISPLAY INVISIBLE (-3150 3050);
FORCEPROP 1 LAST BODY_TYPE PLUMBING
J 0
(-3150 3000);
DISPLAY 1.234043 (-3150 3000);
PAINT GREEN (-3150 3000);
DISPLAY INVISIBLE (-3150 3000);
FORCEPROP 1 LAST HDL_TAP TRUE
J 0
(-2825 2925);
DISPLAY 1.234043 (-2825 2925);
PAINT GREEN (-2825 2925);
DISPLAY INVISIBLE (-2825 2925);
FORCEPROP 1 LAST PATH I154
J 0
(-3150 3050);
DISPLAY 0.936170 (-3150 3050);
PAINT GREEN (-3150 3050);
DISPLAY INVISIBLE (-3150 3050);
FORCEADD TAP..6
(-3150 2950);
FORCEPROP 3 LASTPIN (-3100 2950) SIG_NAME M_C_ODT<3>
J 0
(-3090 2960);
DISPLAY 0.659574 (-3090 2960);
PAINT MONO (-3090 2960);
DISPLAY INVISIBLE (-3090 2960);
FORCEPROP 1 LASTPIN (-3100 2950) BN 3
J 0
(-3150 2960);
DISPLAY 0.617021 (-3150 2960);
PAINT PINK (-3150 2960);
FORCEPROP 2 LAST CDS_LIB mstr_standard
J 0
(-3150 2950);
DISPLAY 0.787234 (-3150 2950);
PAINT MONO (-3150 2950);
DISPLAY INVISIBLE (-3150 2950);
FORCEPROP 1 LAST BODY_TYPE PLUMBING
J 0
(-3150 2900);
DISPLAY 1.234043 (-3150 2900);
PAINT GREEN (-3150 2900);
DISPLAY INVISIBLE (-3150 2900);
FORCEPROP 1 LAST HDL_TAP TRUE
J 0
(-2825 2825);
DISPLAY 1.234043 (-2825 2825);
PAINT GREEN (-2825 2825);
DISPLAY INVISIBLE (-2825 2825);
FORCEPROP 1 LAST PATH I155
J 0
(-3150 2950);
DISPLAY 0.936170 (-3150 2950);
PAINT GREEN (-3150 2950);
DISPLAY INVISIBLE (-3150 2950);
FORCEADD OFFPAGE..1
(-3750 3000);
FORCEPROP 2 LAST $XR1 47 
J 0
(-4061 3000);
DISPLAY 0.638298 (-4061 3000);
PAINT MONO (-4061 3000);
FORCEPROP 2 LAST $XR0 25 
J 0
(-3971 3000);
DISPLAY 0.638298 (-3971 3000);
PAINT MONO (-3971 3000);
FORCEPROP 2 LAST CDS_LIB mstr_standard
J 0
(-3750 3000);
DISPLAY 0.787234 (-3750 3000);
PAINT MONO (-3750 3000);
DISPLAY INVISIBLE (-3750 3000);
FORCEPROP 1 LAST OFFPAGE TRUE
J 0
(-3425 2875);
DISPLAY 0.936170 (-3425 2875);
PAINT GREEN (-3425 2875);
DISPLAY INVISIBLE (-3425 2875);
FORCEPROP 1 LAST COMMENT_BODY TRUE
J 0
(-3625 2900);
DISPLAY 0.936170 (-3625 2900);
PAINT GREEN (-3625 2900);
DISPLAY INVISIBLE (-3625 2900);
FORCEPROP 2 LAST PATH I156
J 0
(-3700 3075);
DISPLAY 0.787234 (-3700 3075);
PAINT MONO (-3700 3075);
DISPLAY INVISIBLE (-3700 3075);
FORCEADD TAP..6
(-3150 2900);
FORCEPROP 3 LASTPIN (-3100 2900) SIG_NAME M_C_ODT<2>
J 0
(-3090 2910);
DISPLAY 0.659574 (-3090 2910);
PAINT MONO (-3090 2910);
DISPLAY INVISIBLE (-3090 2910);
FORCEPROP 1 LASTPIN (-3100 2900) BN 2
J 0
(-3150 2910);
DISPLAY 0.617021 (-3150 2910);
PAINT PINK (-3150 2910);
FORCEPROP 2 LAST CDS_LIB mstr_standard
J 0
(-3150 2900);
DISPLAY 0.787234 (-3150 2900);
PAINT MONO (-3150 2900);
DISPLAY INVISIBLE (-3150 2900);
FORCEPROP 1 LAST BODY_TYPE PLUMBING
J 0
(-3150 2850);
DISPLAY 1.234043 (-3150 2850);
PAINT GREEN (-3150 2850);
DISPLAY INVISIBLE (-3150 2850);
FORCEPROP 1 LAST HDL_TAP TRUE
J 0
(-2825 2775);
DISPLAY 1.234043 (-2825 2775);
PAINT GREEN (-2825 2775);
DISPLAY INVISIBLE (-2825 2775);
FORCEPROP 1 LAST PATH I157
J 0
(-3150 2900);
DISPLAY 0.936170 (-3150 2900);
PAINT GREEN (-3150 2900);
DISPLAY INVISIBLE (-3150 2900);
FORCEADD TAP..6
(-3150 3350);
FORCEPROP 3 LASTPIN (-3100 3350) SIG_NAME M_C_CS_N<7>
J 0
(-3090 3360);
DISPLAY 0.659574 (-3090 3360);
PAINT MONO (-3090 3360);
DISPLAY INVISIBLE (-3090 3360);
FORCEPROP 1 LASTPIN (-3100 3350) BN 7
J 0
(-3150 3360);
DISPLAY 0.617021 (-3150 3360);
PAINT PINK (-3150 3360);
FORCEPROP 2 LAST CDS_LIB mstr_standard
J 0
(-3150 3350);
DISPLAY 0.787234 (-3150 3350);
PAINT MONO (-3150 3350);
DISPLAY INVISIBLE (-3150 3350);
FORCEPROP 1 LAST BODY_TYPE PLUMBING
J 0
(-3150 3300);
DISPLAY 1.234043 (-3150 3300);
PAINT GREEN (-3150 3300);
DISPLAY INVISIBLE (-3150 3300);
FORCEPROP 1 LAST HDL_TAP TRUE
J 0
(-2825 3225);
DISPLAY 1.234043 (-2825 3225);
PAINT GREEN (-2825 3225);
DISPLAY INVISIBLE (-2825 3225);
FORCEPROP 1 LAST PATH I158
J 0
(-3150 3350);
DISPLAY 0.936170 (-3150 3350);
PAINT GREEN (-3150 3350);
DISPLAY INVISIBLE (-3150 3350);
FORCEADD TAP..6
(-3150 3300);
FORCEPROP 3 LASTPIN (-3100 3300) SIG_NAME M_C_CS_N<6>
J 0
(-3090 3310);
DISPLAY 0.659574 (-3090 3310);
PAINT MONO (-3090 3310);
DISPLAY INVISIBLE (-3090 3310);
FORCEPROP 1 LASTPIN (-3100 3300) BN 6
J 0
(-3150 3310);
DISPLAY 0.617021 (-3150 3310);
PAINT PINK (-3150 3310);
FORCEPROP 2 LAST CDS_LIB mstr_standard
J 0
(-3150 3300);
DISPLAY 0.787234 (-3150 3300);
PAINT MONO (-3150 3300);
DISPLAY INVISIBLE (-3150 3300);
FORCEPROP 1 LAST BODY_TYPE PLUMBING
J 0
(-3150 3250);
DISPLAY 1.234043 (-3150 3250);
PAINT GREEN (-3150 3250);
DISPLAY INVISIBLE (-3150 3250);
FORCEPROP 1 LAST HDL_TAP TRUE
J 0
(-2825 3175);
DISPLAY 1.234043 (-2825 3175);
PAINT GREEN (-2825 3175);
DISPLAY INVISIBLE (-2825 3175);
FORCEPROP 1 LAST PATH I159
J 0
(-3150 3300);
DISPLAY 0.936170 (-3150 3300);
PAINT GREEN (-3150 3300);
DISPLAY INVISIBLE (-3150 3300);
FORCEADD TAP..6
R 2
(700 4750);
FORCEPROP 3 LASTPIN (650 4750) SIG_NAME M_C_DQS_DP<13>
J 0
(660 4760);
DISPLAY 0.659574 (660 4760);
PAINT MONO (660 4760);
DISPLAY INVISIBLE (660 4760);
FORCEPROP 1 LASTPIN (650 4750) BN 13
J 2
(700 4760);
DISPLAY 0.617021 (700 4760);
PAINT PINK (700 4760);
FORCEPROP 2 LAST CDS_LIB mstr_standard
J 0
(700 4750);
DISPLAY 0.787234 (700 4750);
PAINT MONO (700 4750);
DISPLAY INVISIBLE (700 4750);
FORCEPROP 1 LAST BODY_TYPE PLUMBING
J 2
(700 4700);
DISPLAY 1.234043 (700 4700);
PAINT GREEN (700 4700);
DISPLAY INVISIBLE (700 4700);
FORCEPROP 1 LAST HDL_TAP TRUE
J 2
(375 4625);
DISPLAY 1.234043 (375 4625);
PAINT WHITE (375 4625);
DISPLAY INVISIBLE (375 4625);
FORCEPROP 1 LAST PATH I16
J 2
(700 4750);
DISPLAY 0.936170 (700 4750);
PAINT GREEN (700 4750);
DISPLAY INVISIBLE (700 4750);
FORCEADD TAP..6
(-3150 3250);
FORCEPROP 3 LASTPIN (-3100 3250) SIG_NAME M_C_CS_N<5>
J 0
(-3090 3260);
DISPLAY 0.659574 (-3090 3260);
PAINT MONO (-3090 3260);
DISPLAY INVISIBLE (-3090 3260);
FORCEPROP 1 LASTPIN (-3100 3250) BN 5
J 0
(-3150 3260);
DISPLAY 0.617021 (-3150 3260);
PAINT PINK (-3150 3260);
FORCEPROP 2 LAST CDS_LIB mstr_standard
J 0
(-3150 3250);
DISPLAY 0.787234 (-3150 3250);
PAINT MONO (-3150 3250);
DISPLAY INVISIBLE (-3150 3250);
FORCEPROP 1 LAST BODY_TYPE PLUMBING
J 0
(-3150 3200);
DISPLAY 1.234043 (-3150 3200);
PAINT GREEN (-3150 3200);
DISPLAY INVISIBLE (-3150 3200);
FORCEPROP 1 LAST HDL_TAP TRUE
J 0
(-2825 3125);
DISPLAY 1.234043 (-2825 3125);
PAINT GREEN (-2825 3125);
DISPLAY INVISIBLE (-2825 3125);
FORCEPROP 1 LAST PATH I160
J 0
(-3150 3250);
DISPLAY 0.936170 (-3150 3250);
PAINT GREEN (-3150 3250);
DISPLAY INVISIBLE (-3150 3250);
FORCEADD TAP..6
(-3150 3200);
FORCEPROP 3 LASTPIN (-3100 3200) SIG_NAME M_C_CS_N<4>
J 0
(-3090 3210);
DISPLAY 0.659574 (-3090 3210);
PAINT MONO (-3090 3210);
DISPLAY INVISIBLE (-3090 3210);
FORCEPROP 1 LASTPIN (-3100 3200) BN 4
J 0
(-3150 3210);
DISPLAY 0.617021 (-3150 3210);
PAINT PINK (-3150 3210);
FORCEPROP 2 LAST CDS_LIB mstr_standard
J 0
(-3150 3200);
DISPLAY 0.787234 (-3150 3200);
PAINT MONO (-3150 3200);
DISPLAY INVISIBLE (-3150 3200);
FORCEPROP 1 LAST BODY_TYPE PLUMBING
J 0
(-3150 3150);
DISPLAY 1.234043 (-3150 3150);
PAINT GREEN (-3150 3150);
DISPLAY INVISIBLE (-3150 3150);
FORCEPROP 1 LAST HDL_TAP TRUE
J 0
(-2825 3075);
DISPLAY 1.234043 (-2825 3075);
PAINT GREEN (-2825 3075);
DISPLAY INVISIBLE (-2825 3075);
FORCEPROP 1 LAST PATH I161
J 0
(-3150 3200);
DISPLAY 0.936170 (-3150 3200);
PAINT GREEN (-3150 3200);
DISPLAY INVISIBLE (-3150 3200);
FORCEADD OFFPAGE..1
(-3750 3400);
FORCEPROP 2 LAST $XR1 47 
J 0
(-4061 3400);
DISPLAY 0.638298 (-4061 3400);
PAINT MONO (-4061 3400);
FORCEPROP 2 LAST $XR0 25 
J 0
(-3971 3400);
DISPLAY 0.638298 (-3971 3400);
PAINT MONO (-3971 3400);
FORCEPROP 2 LAST CDS_LIB mstr_standard
J 0
(-3750 3400);
DISPLAY 0.787234 (-3750 3400);
PAINT MONO (-3750 3400);
DISPLAY INVISIBLE (-3750 3400);
FORCEPROP 1 LAST OFFPAGE TRUE
J 0
(-3425 3275);
DISPLAY 0.936170 (-3425 3275);
PAINT GREEN (-3425 3275);
DISPLAY INVISIBLE (-3425 3275);
FORCEPROP 1 LAST COMMENT_BODY TRUE
J 0
(-3625 3300);
DISPLAY 0.936170 (-3625 3300);
PAINT GREEN (-3625 3300);
DISPLAY INVISIBLE (-3625 3300);
FORCEPROP 2 LAST PATH I162
J 0
(-3700 3475);
DISPLAY 0.787234 (-3700 3475);
PAINT MONO (-3700 3475);
DISPLAY INVISIBLE (-3700 3475);
FORCEADD TAP..6
(-3150 3650);
FORCEPROP 3 LASTPIN (-3100 3650) SIG_NAME M_C_CLK_DP<3>
J 0
(-3090 3660);
DISPLAY 0.659574 (-3090 3660);
PAINT MONO (-3090 3660);
DISPLAY INVISIBLE (-3090 3660);
FORCEPROP 1 LASTPIN (-3100 3650) BN 3
J 0
(-3150 3660);
DISPLAY 0.617021 (-3150 3660);
PAINT PINK (-3150 3660);
FORCEPROP 2 LAST CDS_LIB mstr_standard
J 0
(-3150 3650);
DISPLAY 0.787234 (-3150 3650);
PAINT MONO (-3150 3650);
DISPLAY INVISIBLE (-3150 3650);
FORCEPROP 1 LAST BODY_TYPE PLUMBING
J 0
(-3150 3600);
DISPLAY 1.234043 (-3150 3600);
PAINT GREEN (-3150 3600);
DISPLAY INVISIBLE (-3150 3600);
FORCEPROP 1 LAST HDL_TAP TRUE
J 0
(-2825 3525);
DISPLAY 1.234043 (-2825 3525);
PAINT GREEN (-2825 3525);
DISPLAY INVISIBLE (-2825 3525);
FORCEPROP 1 LAST PATH I163
J 0
(-3150 3650);
DISPLAY 0.936170 (-3150 3650);
PAINT GREEN (-3150 3650);
DISPLAY INVISIBLE (-3150 3650);
FORCEADD TAP..6
(-3150 3550);
FORCEPROP 3 LASTPIN (-3100 3550) SIG_NAME M_C_CLK_DP<2>
J 0
(-3090 3560);
DISPLAY 0.659574 (-3090 3560);
PAINT MONO (-3090 3560);
DISPLAY INVISIBLE (-3090 3560);
FORCEPROP 1 LASTPIN (-3100 3550) BN 2
J 0
(-3150 3560);
DISPLAY 0.617021 (-3150 3560);
PAINT PINK (-3150 3560);
FORCEPROP 2 LAST CDS_LIB mstr_standard
J 0
(-3150 3550);
DISPLAY 0.787234 (-3150 3550);
PAINT MONO (-3150 3550);
DISPLAY INVISIBLE (-3150 3550);
FORCEPROP 1 LAST BODY_TYPE PLUMBING
J 0
(-3150 3500);
DISPLAY 1.234043 (-3150 3500);
PAINT GREEN (-3150 3500);
DISPLAY INVISIBLE (-3150 3500);
FORCEPROP 1 LAST HDL_TAP TRUE
J 0
(-2825 3425);
DISPLAY 1.234043 (-2825 3425);
PAINT GREEN (-2825 3425);
DISPLAY INVISIBLE (-2825 3425);
FORCEPROP 1 LAST PATH I164
J 0
(-3150 3550);
DISPLAY 0.936170 (-3150 3550);
PAINT GREEN (-3150 3550);
DISPLAY INVISIBLE (-3150 3550);
FORCEADD TAP..6
(-3350 3600);
FORCEPROP 3 LASTPIN (-3300 3600) SIG_NAME M_C_CLK_DN<3>
J 0
(-3290 3610);
DISPLAY 0.659574 (-3290 3610);
PAINT MONO (-3290 3610);
DISPLAY INVISIBLE (-3290 3610);
FORCEPROP 1 LASTPIN (-3300 3600) BN 3
J 0
(-3350 3610);
DISPLAY 0.617021 (-3350 3610);
PAINT PINK (-3350 3610);
FORCEPROP 2 LAST CDS_LIB mstr_standard
J 0
(-3350 3600);
DISPLAY 0.787234 (-3350 3600);
PAINT MONO (-3350 3600);
DISPLAY INVISIBLE (-3350 3600);
FORCEPROP 1 LAST BODY_TYPE PLUMBING
J 0
(-3350 3550);
DISPLAY 1.234043 (-3350 3550);
PAINT GREEN (-3350 3550);
DISPLAY INVISIBLE (-3350 3550);
FORCEPROP 1 LAST HDL_TAP TRUE
J 0
(-3025 3475);
DISPLAY 1.234043 (-3025 3475);
PAINT GREEN (-3025 3475);
DISPLAY INVISIBLE (-3025 3475);
FORCEPROP 1 LAST PATH I165
J 0
(-3350 3600);
DISPLAY 0.936170 (-3350 3600);
PAINT GREEN (-3350 3600);
DISPLAY INVISIBLE (-3350 3600);
FORCEADD TAP..6
(-3350 3500);
FORCEPROP 3 LASTPIN (-3300 3500) SIG_NAME M_C_CLK_DN<2>
J 0
(-3290 3510);
DISPLAY 0.659574 (-3290 3510);
PAINT MONO (-3290 3510);
DISPLAY INVISIBLE (-3290 3510);
FORCEPROP 1 LASTPIN (-3300 3500) BN 2
J 0
(-3350 3510);
DISPLAY 0.617021 (-3350 3510);
PAINT PINK (-3350 3510);
FORCEPROP 2 LAST CDS_LIB mstr_standard
J 0
(-3350 3500);
DISPLAY 0.787234 (-3350 3500);
PAINT MONO (-3350 3500);
DISPLAY INVISIBLE (-3350 3500);
FORCEPROP 1 LAST BODY_TYPE PLUMBING
J 0
(-3350 3450);
DISPLAY 1.234043 (-3350 3450);
PAINT GREEN (-3350 3450);
DISPLAY INVISIBLE (-3350 3450);
FORCEPROP 1 LAST HDL_TAP TRUE
J 0
(-3025 3375);
DISPLAY 1.234043 (-3025 3375);
PAINT GREEN (-3025 3375);
DISPLAY INVISIBLE (-3025 3375);
FORCEPROP 1 LAST PATH I166
J 0
(-3350 3500);
DISPLAY 0.936170 (-3350 3500);
PAINT GREEN (-3350 3500);
DISPLAY INVISIBLE (-3350 3500);
FORCEADD OFFPAGE..1
(-3950 3700);
FORCEPROP 2 LAST $XR1 47 
J 0
(-4261 3700);
DISPLAY 0.638298 (-4261 3700);
PAINT MONO (-4261 3700);
FORCEPROP 2 LAST $XR0 25 
J 0
(-4171 3700);
DISPLAY 0.638298 (-4171 3700);
PAINT MONO (-4171 3700);
FORCEPROP 2 LAST CDS_LIB mstr_standard
J 0
(-3950 3700);
DISPLAY 0.787234 (-3950 3700);
PAINT MONO (-3950 3700);
DISPLAY INVISIBLE (-3950 3700);
FORCEPROP 1 LAST OFFPAGE TRUE
J 0
(-3625 3575);
DISPLAY 0.936170 (-3625 3575);
PAINT GREEN (-3625 3575);
DISPLAY INVISIBLE (-3625 3575);
FORCEPROP 1 LAST COMMENT_BODY TRUE
J 0
(-3825 3600);
DISPLAY 0.936170 (-3825 3600);
PAINT GREEN (-3825 3600);
DISPLAY INVISIBLE (-3825 3600);
FORCEPROP 2 LAST PATH I167
J 0
(-3900 3775);
DISPLAY 0.787234 (-3900 3775);
PAINT MONO (-3900 3775);
DISPLAY INVISIBLE (-3900 3775);
FORCEADD OFFPAGE..1
(-3950 3650);
FORCEPROP 2 LAST $XR1 47 
J 0
(-4261 3650);
DISPLAY 0.638298 (-4261 3650);
PAINT MONO (-4261 3650);
FORCEPROP 2 LAST $XR0 25 
J 0
(-4171 3650);
DISPLAY 0.638298 (-4171 3650);
PAINT MONO (-4171 3650);
FORCEPROP 2 LAST CDS_LIB mstr_standard
J 0
(-3950 3650);
DISPLAY 0.787234 (-3950 3650);
PAINT MONO (-3950 3650);
DISPLAY INVISIBLE (-3950 3650);
FORCEPROP 1 LAST OFFPAGE TRUE
J 0
(-3625 3525);
DISPLAY 0.936170 (-3625 3525);
PAINT GREEN (-3625 3525);
DISPLAY INVISIBLE (-3625 3525);
FORCEPROP 1 LAST COMMENT_BODY TRUE
J 0
(-3825 3550);
DISPLAY 0.936170 (-3825 3550);
PAINT GREEN (-3825 3550);
DISPLAY INVISIBLE (-3825 3550);
FORCEPROP 2 LAST PATH I168
J 0
(-3900 3725);
DISPLAY 0.787234 (-3900 3725);
PAINT MONO (-3900 3725);
DISPLAY INVISIBLE (-3900 3725);
FORCEADD OFFPAGE..1
(-3750 1800);
FORCEPROP 2 LAST $XR5 47 
J 0
(-4451 1800);
DISPLAY 0.638298 (-4451 1800);
PAINT MONO (-4451 1800);
FORCEPROP 2 LAST $XR4 46 
J 0
(-4361 1800);
DISPLAY 0.638298 (-4361 1800);
PAINT MONO (-4361 1800);
FORCEPROP 2 LAST $XR3 45 
J 0
(-4271 1800);
DISPLAY 0.638298 (-4271 1800);
PAINT MONO (-4271 1800);
FORCEPROP 2 LAST $XR2 44 
J 0
(-4181 1800);
DISPLAY 0.638298 (-4181 1800);
PAINT MONO (-4181 1800);
FORCEPROP 2 LAST $XR1 43 
J 0
(-4091 1800);
DISPLAY 0.638298 (-4091 1800);
PAINT MONO (-4091 1800);
FORCEPROP 2 LAST $XR0 99 
J 0
(-4001 1800);
DISPLAY 0.638298 (-4001 1800);
PAINT MONO (-4001 1800);
FORCEPROP 2 LAST CDS_LIB mstr_standard
J 0
(-3750 1800);
DISPLAY 0.787234 (-3750 1800);
PAINT MONO (-3750 1800);
DISPLAY INVISIBLE (-3750 1800);
FORCEPROP 1 LAST OFFPAGE TRUE
J 0
(-3425 1675);
DISPLAY 0.936170 (-3425 1675);
PAINT GREEN (-3425 1675);
DISPLAY INVISIBLE (-3425 1675);
FORCEPROP 1 LAST COMMENT_BODY TRUE
J 0
(-3625 1700);
DISPLAY 0.936170 (-3625 1700);
PAINT GREEN (-3625 1700);
DISPLAY INVISIBLE (-3625 1700);
FORCEPROP 2 LAST PATH I169
J 0
(-3700 1875);
DISPLAY 0.787234 (-3700 1875);
PAINT MONO (-3700 1875);
DISPLAY INVISIBLE (-3700 1875);
FORCEADD TAP..6
R 2
(700 4650);
FORCEPROP 3 LASTPIN (650 4650) SIG_NAME M_C_DQS_DP<12>
J 0
(660 4660);
DISPLAY 0.659574 (660 4660);
PAINT MONO (660 4660);
DISPLAY INVISIBLE (660 4660);
FORCEPROP 1 LASTPIN (650 4650) BN 12
J 2
(700 4660);
DISPLAY 0.617021 (700 4660);
PAINT PINK (700 4660);
FORCEPROP 2 LAST CDS_LIB mstr_standard
J 0
(700 4650);
DISPLAY 0.787234 (700 4650);
PAINT MONO (700 4650);
DISPLAY INVISIBLE (700 4650);
FORCEPROP 1 LAST BODY_TYPE PLUMBING
J 2
(700 4600);
DISPLAY 1.234043 (700 4600);
PAINT GREEN (700 4600);
DISPLAY INVISIBLE (700 4600);
FORCEPROP 1 LAST HDL_TAP TRUE
J 2
(375 4525);
DISPLAY 1.234043 (375 4525);
PAINT WHITE (375 4525);
DISPLAY INVISIBLE (375 4525);
FORCEPROP 1 LAST PATH I17
J 2
(700 4650);
DISPLAY 0.936170 (700 4650);
PAINT GREEN (700 4650);
DISPLAY INVISIBLE (700 4650);
FORCEADD OFFPAGE..6
(-3750 1850);
FORCEPROP 2 LAST $XR5 99 
J 0
(-4479 1850);
DISPLAY 0.638298 (-4479 1850);
PAINT MONO (-4479 1850);
FORCEPROP 2 LAST $XR4 47 
J 0
(-4389 1850);
DISPLAY 0.638298 (-4389 1850);
PAINT MONO (-4389 1850);
FORCEPROP 2 LAST $XR3 46 
J 0
(-4299 1850);
DISPLAY 0.638298 (-4299 1850);
PAINT MONO (-4299 1850);
FORCEPROP 2 LAST $XR2 45 
J 0
(-4209 1850);
DISPLAY 0.638298 (-4209 1850);
PAINT MONO (-4209 1850);
FORCEPROP 2 LAST $XR1 44 
J 0
(-4119 1850);
DISPLAY 0.638298 (-4119 1850);
PAINT MONO (-4119 1850);
FORCEPROP 2 LAST $XR0 43 
J 0
(-4029 1850);
DISPLAY 0.638298 (-4029 1850);
PAINT MONO (-4029 1850);
FORCEPROP 2 LAST CDS_LIB mstr_standard
J 0
(-3750 1850);
DISPLAY 0.787234 (-3750 1850);
PAINT MONO (-3750 1850);
DISPLAY INVISIBLE (-3750 1850);
FORCEPROP 1 LAST OFFPAGE TRUE
J 0
(-3425 1725);
DISPLAY 0.936170 (-3425 1725);
PAINT GREEN (-3425 1725);
DISPLAY INVISIBLE (-3425 1725);
FORCEPROP 1 LAST COMMENT_BODY TRUE
J 0
(-3650 1775);
DISPLAY 0.936170 (-3650 1775);
PAINT GREEN (-3650 1775);
DISPLAY INVISIBLE (-3650 1775);
FORCEPROP 2 LAST PATH I170
J 0
(-3700 1925);
DISPLAY 0.787234 (-3700 1925);
PAINT MONO (-3700 1925);
DISPLAY INVISIBLE (-3700 1925);
FORCEADD SCONN288_H44441003..4
(-100 2000);
FORCEPROP 1 LAST LOCATION J6U2
J 0
(-550 3100);
DISPLAY 0.617021 (-550 3100);
PAINT AQUA (-550 3100);
FORCEPROP 2 LASTPIN (-600 2550) $PN 77
J 2
(-610 2560);
DISPLAY 0.617021 (-610 2560);
PAINT ORANGE (-610 2560);
FORCEPROP 2 LASTPIN (-600 2500) $PN 221
J 2
(-610 2510);
DISPLAY 0.617021 (-610 2510);
PAINT ORANGE (-610 2510);
FORCEPROP 2 LASTPIN (-600 2850) $PN 142
J 2
(-610 2860);
DISPLAY 0.617021 (-610 2860);
PAINT ORANGE (-610 2860);
FORCEPROP 2 LASTPIN (-600 2800) $PN 143
J 2
(-610 2810);
DISPLAY 0.617021 (-610 2810);
PAINT ORANGE (-610 2810);
FORCEPROP 2 LASTPIN (-600 2750) $PN 288
J 2
(-610 2760);
DISPLAY 0.617021 (-610 2760);
PAINT ORANGE (-610 2760);
FORCEPROP 2 LASTPIN (-600 2700) $PN 286
J 2
(-610 2710);
DISPLAY 0.617021 (-610 2710);
PAINT ORANGE (-610 2710);
FORCEPROP 2 LASTPIN (-600 2650) $PN 287
J 2
(-610 2660);
DISPLAY 0.617021 (-610 2660);
PAINT ORANGE (-610 2660);
FORCEPROP 2 LASTPIN (-600 2400) $PN 59
J 2
(-610 2410);
DISPLAY 0.617021 (-610 2410);
PAINT ORANGE (-610 2410);
FORCEPROP 2 LASTPIN (-600 2350) $PN 61
J 2
(-610 2360);
DISPLAY 0.617021 (-610 2360);
PAINT ORANGE (-610 2360);
FORCEPROP 2 LASTPIN (-600 2300) $PN 64
J 2
(-610 2310);
DISPLAY 0.617021 (-610 2310);
PAINT ORANGE (-610 2310);
FORCEPROP 2 LASTPIN (-600 2250) $PN 67
J 2
(-610 2260);
DISPLAY 0.617021 (-610 2260);
PAINT ORANGE (-610 2260);
FORCEPROP 2 LASTPIN (-600 2200) $PN 70
J 2
(-610 2210);
DISPLAY 0.617021 (-610 2210);
PAINT ORANGE (-610 2210);
FORCEPROP 2 LASTPIN (-600 2150) $PN 73
J 2
(-610 2160);
DISPLAY 0.617021 (-610 2160);
PAINT ORANGE (-610 2160);
FORCEPROP 2 LASTPIN (-600 2100) $PN 76
J 2
(-610 2110);
DISPLAY 0.617021 (-610 2110);
PAINT ORANGE (-610 2110);
FORCEPROP 2 LASTPIN (-600 2050) $PN 80
J 2
(-610 2060);
DISPLAY 0.617021 (-610 2060);
PAINT ORANGE (-610 2060);
FORCEPROP 2 LASTPIN (-600 2000) $PN 83
J 2
(-610 2010);
DISPLAY 0.617021 (-610 2010);
PAINT ORANGE (-610 2010);
FORCEPROP 2 LASTPIN (-600 1950) $PN 85
J 2
(-610 1960);
DISPLAY 0.617021 (-610 1960);
PAINT ORANGE (-610 1960);
FORCEPROP 2 LASTPIN (-600 1900) $PN 88
J 2
(-610 1910);
DISPLAY 0.617021 (-610 1910);
PAINT ORANGE (-610 1910);
FORCEPROP 2 LASTPIN (-600 1850) $PN 90
J 2
(-610 1860);
DISPLAY 0.617021 (-610 1860);
PAINT ORANGE (-610 1860);
FORCEPROP 2 LASTPIN (-600 1800) $PN 92
J 2
(-610 1810);
DISPLAY 0.617021 (-610 1810);
PAINT ORANGE (-610 1810);
FORCEPROP 2 LASTPIN (-600 1750) $PN 204
J 2
(-610 1760);
DISPLAY 0.617021 (-610 1760);
PAINT ORANGE (-610 1760);
FORCEPROP 2 LASTPIN (-600 1650) $PN 209
J 2
(-610 1660);
DISPLAY 0.617021 (-610 1660);
PAINT ORANGE (-610 1660);
FORCEPROP 2 LASTPIN (-600 1600) $PN 212
J 2
(-610 1610);
DISPLAY 0.617021 (-610 1610);
PAINT ORANGE (-610 1610);
FORCEPROP 2 LASTPIN (-600 1550) $PN 215
J 2
(-610 1560);
DISPLAY 0.617021 (-610 1560);
PAINT ORANGE (-610 1560);
FORCEPROP 2 LASTPIN (-600 1500) $PN 217
J 2
(-610 1510);
DISPLAY 0.617021 (-610 1510);
PAINT ORANGE (-610 1510);
FORCEPROP 2 LASTPIN (-600 1450) $PN 220
J 2
(-610 1460);
DISPLAY 0.617021 (-610 1460);
PAINT ORANGE (-610 1460);
FORCEPROP 2 LASTPIN (-600 1400) $PN 223
J 2
(-610 1410);
DISPLAY 0.617021 (-610 1410);
PAINT ORANGE (-610 1410);
FORCEPROP 2 LASTPIN (-600 1350) $PN 226
J 2
(-610 1360);
DISPLAY 0.617021 (-610 1360);
PAINT ORANGE (-610 1360);
FORCEPROP 2 LASTPIN (-600 1300) $PN 229
J 2
(-610 1310);
DISPLAY 0.617021 (-610 1310);
PAINT ORANGE (-610 1310);
FORCEPROP 2 LASTPIN (-600 1250) $PN 231
J 2
(-610 1260);
DISPLAY 0.617021 (-610 1260);
PAINT ORANGE (-610 1260);
FORCEPROP 2 LASTPIN (-600 1200) $PN 233
J 2
(-610 1210);
DISPLAY 0.617021 (-610 1210);
PAINT ORANGE (-610 1210);
FORCEPROP 2 LASTPIN (-600 1150) $PN 236
J 2
(-610 1160);
DISPLAY 0.617021 (-610 1160);
PAINT ORANGE (-610 1160);
FORCEPROP 2 LASTPIN (400 2850) $PN 1
J 0
(410 2860);
DISPLAY 0.617021 (410 2860);
PAINT ORANGE (410 2860);
FORCEPROP 2 LASTPIN (400 2800) $PN 145
J 0
(410 2810);
DISPLAY 0.617021 (410 2810);
PAINT ORANGE (410 2810);
FORCEPROP 1 LAST PART_NUMBER H44441-003
J 0
(-550 950);
DISPLAY 0.617021 (-550 950);
PAINT BLUE (-550 950);
FORCEPROP 1 LAST MATERIAL SCONN
J 0
(-550 3050);
DISPLAY 0.617021 (-550 3050);
PAINT SKYBLUE (-550 3050);
FORCEPROP 2 LASTPIN (-600 1700) $PN 206
J 2
(-610 1710);
DISPLAY 0.617021 (-610 1710);
PAINT ORANGE (-610 1710);
FORCEPROP 0 LAST BOM_SS NOPOP
J 0
(-265 3045);
DISPLAY 1.021277 (-265 3045);
PAINT BROWN (-265 3045);
DISPLAY BOTH (-265 3045);
FORCEPROP 1 LAST PACK_TYPE PIP
J 0
(-550 3150);
PAINT SKYBLUE (-550 3150);
DISPLAY INVISIBLE (-550 3150);
FORCEPROP 2 LAST BOM_COST MEM
J 0
(-100 2000);
PAINT ORANGE (-100 2000);
DISPLAY INVISIBLE (-100 2000);
FORCEPROP 2 LAST CDS_LIB mstr_sconn
J 0
(-100 2000);
PAINT ORANGE (-100 2000);
DISPLAY INVISIBLE (-100 2000);
FORCEPROP 2 LAST SEC_TYPE PIP
J 0
(-550 3150);
DISPLAY 1.021277 (-550 3150);
PAINT ORANGE (-550 3150);
DISPLAY INVISIBLE (-550 3150);
FORCEPROP 2 LAST SEC 4
J 0
(-550 3150);
DISPLAY 0.680851 (-550 3150);
PAINT MONO (-550 3150);
DISPLAY INVISIBLE (-550 3150);
FORCEPROP 2 LAST CDS_LOCATION J6U2
J 0
(-550 3100);
DISPLAY 0.617021 (-550 3100);
PAINT AQUA (-550 3100);
DISPLAY INVISIBLE (-550 3100);
FORCEPROP 1 LAST PATH I171
J 0
(-100 3050);
PAINT GREEN (-100 3050);
DISPLAY INVISIBLE (-100 3050);
FORCEPROP 2 LAST ROOM DDR4_CH_C1
J 0
(-100 2000);
PAINT ORANGE (-100 2000);
DISPLAY INVISIBLE (-100 2000);
FORCEADD GND..1
R 2
(2500 1300);
FORCEPROP 3 LASTPIN (2500 1350) SIG_NAME GND\g
J 0
(2510 1360);
DISPLAY 0.659574 (2510 1360);
PAINT MONO (2510 1360);
DISPLAY INVISIBLE (2510 1360);
FORCEPROP 1 LAST VOLTAGE 0
J 0
(2500 1300);
PAINT SKYBLUE (2500 1300);
DISPLAY INVISIBLE (2500 1300);
FORCEPROP 2 LAST CDS_LIB mstr_symbols
J 0
(2500 1300);
DISPLAY 0.787234 (2500 1300);
PAINT MONO (2500 1300);
DISPLAY INVISIBLE (2500 1300);
FORCEPROP 1 LAST SIZE 1B
J 2
(2425 1250);
DISPLAY 1.170213 (2425 1250);
PAINT GREEN (2425 1250);
DISPLAY INVISIBLE (2425 1250);
FORCEPROP 2 LAST BOM_COST MEM
J 0
(2500 1305);
PAINT ORANGE (2500 1305);
DISPLAY INVISIBLE (2500 1305);
FORCEPROP 1 LAST BODY_TYPE PLUMBING
J 2
(2545 1257);
DISPLAY 0.340426 (2545 1257);
PAINT GREEN (2545 1257);
DISPLAY INVISIBLE (2545 1257);
FORCEPROP 1 LAST PATH I172
J 2
(2425 1300);
DISPLAY 1.404255 (2425 1300);
PAINT GREEN (2425 1300);
DISPLAY INVISIBLE (2425 1300);
FORCEPROP 2 LAST ROOM DDR4_CH_B
J 0
(2500 1305);
PAINT ORANGE (2500 1305);
DISPLAY INVISIBLE (2500 1305);
FORCEPROP 1 LAST HDL_POWER GND
J 2
(2500 1450);
DISPLAY 0.553191 (2500 1450);
PAINT GREEN (2500 1450);
DISPLAY INVISIBLE (2500 1450);
FORCEADD OFFPAGE..5
(-4125 2500);
FORCEPROP 2 LAST $XR23 94 
J 0
(-4739 2536);
DISPLAY 0.638298 (-4739 2536);
PAINT MONO (-4739 2536);
FORCEPROP 2 LAST $XR22 88 
J 0
(-4649 2536);
DISPLAY 0.638298 (-4649 2536);
PAINT MONO (-4649 2536);
FORCEPROP 2 LAST $XR21 87 
J 0
(-4559 2536);
DISPLAY 0.638298 (-4559 2536);
PAINT MONO (-4559 2536);
FORCEPROP 2 LAST $XR20 86 
J 0
(-4469 2536);
DISPLAY 0.638298 (-4469 2536);
PAINT MONO (-4469 2536);
FORCEPROP 2 LAST $XR19 85 
J 0
(-4379 2536);
DISPLAY 0.638298 (-4379 2536);
PAINT MONO (-4379 2536);
FORCEPROP 2 LAST $XR18 84 
J 0
(-5099 2464);
DISPLAY 0.638298 (-5099 2464);
PAINT MONO (-5099 2464);
FORCEPROP 2 LAST $XR17 83 
J 0
(-5009 2464);
DISPLAY 0.638298 (-5009 2464);
PAINT MONO (-5009 2464);
FORCEPROP 2 LAST $XR16 82 
J 0
(-4919 2464);
DISPLAY 0.638298 (-4919 2464);
PAINT MONO (-4919 2464);
FORCEPROP 2 LAST $XR15 81 
J 0
(-4829 2464);
DISPLAY 0.638298 (-4829 2464);
PAINT MONO (-4829 2464);
FORCEPROP 2 LAST $XR14 80 
J 0
(-4739 2464);
DISPLAY 0.638298 (-4739 2464);
PAINT MONO (-4739 2464);
FORCEPROP 2 LAST $XR13 79 
J 0
(-4649 2464);
DISPLAY 0.638298 (-4649 2464);
PAINT MONO (-4649 2464);
FORCEPROP 2 LAST $XR12 78 
J 0
(-4559 2464);
DISPLAY 0.638298 (-4559 2464);
PAINT MONO (-4559 2464);
FORCEPROP 2 LAST $XR11 77 
J 0
(-4469 2464);
DISPLAY 0.638298 (-4469 2464);
PAINT MONO (-4469 2464);
FORCEPROP 2 LAST $XR10 54 
J 0
(-4379 2464);
DISPLAY 0.638298 (-4379 2464);
PAINT MONO (-4379 2464);
FORCEPROP 2 LAST $XR9 53 
J 0
(-5189 2500);
DISPLAY 0.638298 (-5189 2500);
PAINT MONO (-5189 2500);
FORCEPROP 2 LAST $XR8 52 
J 0
(-5099 2500);
DISPLAY 0.638298 (-5099 2500);
PAINT MONO (-5099 2500);
FORCEPROP 2 LAST $XR7 51 
J 0
(-5009 2500);
DISPLAY 0.638298 (-5009 2500);
PAINT MONO (-5009 2500);
FORCEPROP 2 LAST $XR6 50 
J 0
(-4919 2500);
DISPLAY 0.638298 (-4919 2500);
PAINT MONO (-4919 2500);
FORCEPROP 2 LAST $XR5 49 
J 0
(-4829 2500);
DISPLAY 0.638298 (-4829 2500);
PAINT MONO (-4829 2500);
FORCEPROP 2 LAST $XR4 47 
J 0
(-4739 2500);
DISPLAY 0.638298 (-4739 2500);
PAINT MONO (-4739 2500);
FORCEPROP 2 LAST $XR3 46 
J 0
(-4649 2500);
DISPLAY 0.638298 (-4649 2500);
PAINT MONO (-4649 2500);
FORCEPROP 2 LAST $XR2 45 
J 0
(-4559 2500);
DISPLAY 0.638298 (-4559 2500);
PAINT MONO (-4559 2500);
FORCEPROP 2 LAST $XR1 44 
J 0
(-4469 2500);
DISPLAY 0.638298 (-4469 2500);
PAINT MONO (-4469 2500);
FORCEPROP 2 LAST $XR0 43 
J 0
(-4379 2500);
DISPLAY 0.638298 (-4379 2500);
PAINT MONO (-4379 2500);
FORCEPROP 2 LAST CDS_LIB mstr_standard
J 0
(-4125 2500);
DISPLAY 0.787234 (-4125 2500);
PAINT MONO (-4125 2500);
DISPLAY INVISIBLE (-4125 2500);
FORCEPROP 1 LAST OFFPAGE TRUE
J 0
(-3800 2375);
DISPLAY 1.404255 (-3800 2375);
PAINT GREEN (-3800 2375);
DISPLAY INVISIBLE (-3800 2375);
FORCEPROP 1 LAST COMMENT_BODY TRUE
J 0
(-4025 2425);
DISPLAY 1.404255 (-4025 2425);
PAINT GREEN (-4025 2425);
DISPLAY INVISIBLE (-4025 2425);
FORCEPROP 2 LAST PATH I173
J 0
(-4075 2575);
DISPLAY 0.787234 (-4075 2575);
PAINT ORANGE (-4075 2575);
DISPLAY INVISIBLE (-4075 2575);
FORCEADD CAP_A..1
R 2
(-4650 1500);
FORCEPROP 1 LAST LOCATION C6U17
J 2
(-4700 1600);
DISPLAY 0.617021 (-4700 1600);
PAINT AQUA (-4700 1600);
FORCEPROP 1 LAST VALUE 0.01UF
J 2
(-4700 1550);
DISPLAY 0.617021 (-4700 1550);
PAINT SKYBLUE (-4700 1550);
FORCEPROP 1 LAST PACK_TYPE 0402V
J 2
(-4700 1300);
DISPLAY 0.617021 (-4700 1300);
PAINT SKYBLUE (-4700 1300);
FORCEPROP 1 LAST VOLTAGE 25V
J 2
(-4700 1500);
DISPLAY 0.617021 (-4700 1500);
PAINT SKYBLUE (-4700 1500);
FORCEPROP 1 LAST MATERIAL X7R
J 2
(-4700 1400);
DISPLAY 0.617021 (-4700 1400);
PAINT SKYBLUE (-4700 1400);
FORCEPROP 1 LASTPIN (-4650 1600) $PN 1
J 2
(-4660 1580);
DISPLAY 0.617021 (-4660 1580);
PAINT ORANGE (-4660 1580);
FORCEPROP 1 LASTPIN (-4650 1400) $PN 2
J 2
(-4660 1380);
DISPLAY 0.617021 (-4660 1380);
PAINT ORANGE (-4660 1380);
FORCEPROP 1 LAST PART_NUMBER A36096-045
J 2
(-4700 1350);
DISPLAY 0.617021 (-4700 1350);
PAINT BLUE (-4700 1350);
FORCEPROP 1 LAST TOLERANCE 10%
J 2
(-4700 1450);
DISPLAY 0.617021 (-4700 1450);
PAINT SKYBLUE (-4700 1450);
FORCEPROP 2 LAST CDS_LOCATION C6U17
J 2
(-4700 1600);
DISPLAY 0.617021 (-4700 1600);
PAINT AQUA (-4700 1600);
DISPLAY INVISIBLE (-4700 1600);
FORCEPROP 2 LAST BOM_COST MEM
J 0
(-4650 1500);
PAINT ORANGE (-4650 1500);
DISPLAY INVISIBLE (-4650 1500);
FORCEPROP 2 LAST CDS_LIB dev_discrete
J 0
(-4650 1500);
PAINT ORANGE (-4650 1500);
DISPLAY INVISIBLE (-4650 1500);
FORCEPROP 2 LAST CDS_SEC 1
J 0
(-4700 1650);
PAINT ORANGE (-4700 1650);
DISPLAY INVISIBLE (-4700 1650);
FORCEPROP 2 LAST SEC_TYPE 0402V
J 0
(-4700 1700);
DISPLAY 1.021277 (-4700 1700);
PAINT ORANGE (-4700 1700);
DISPLAY INVISIBLE (-4700 1700);
FORCEPROP 2 LAST SEC 1
J 0
(-4700 1700);
PAINT MONO (-4700 1700);
DISPLAY INVISIBLE (-4700 1700);
FORCEPROP 1 LAST PATH I176
J 2
(-4700 1650);
DISPLAY 0.978723 (-4700 1650);
PAINT WHITE (-4700 1650);
DISPLAY INVISIBLE (-4700 1650);
FORCEPROP 2 LAST ROOM DDR4_CH_B
J 0
(-4650 1500);
PAINT ORANGE (-4650 1500);
DISPLAY INVISIBLE (-4650 1500);
FORCEADD GND..1
(-4650 1250);
FORCEPROP 3 LASTPIN (-4650 1300) SIG_NAME GND\g
J 0
(-4640 1310);
DISPLAY 0.659574 (-4640 1310);
PAINT MONO (-4640 1310);
DISPLAY INVISIBLE (-4640 1310);
FORCEPROP 1 LAST VOLTAGE 0
J 0
(-4650 1250);
PAINT SKYBLUE (-4650 1250);
DISPLAY INVISIBLE (-4650 1250);
FORCEPROP 1 LAST SIZE 1B
J 0
(-4575 1200);
DISPLAY 1.787234 (-4575 1200);
PAINT GREEN (-4575 1200);
DISPLAY INVISIBLE (-4575 1200);
FORCEPROP 2 LAST BOM_COST MEM
J 0
(-4650 1255);
PAINT ORANGE (-4650 1255);
DISPLAY INVISIBLE (-4650 1255);
FORCEPROP 2 LAST CDS_LIB mstr_symbols
J 0
(-4650 1250);
PAINT ORANGE (-4650 1250);
DISPLAY INVISIBLE (-4650 1250);
FORCEPROP 1 LAST BODY_TYPE PLUMBING
J 0
(-4695 1207);
DISPLAY 0.340426 (-4695 1207);
PAINT GREEN (-4695 1207);
DISPLAY INVISIBLE (-4695 1207);
FORCEPROP 1 LAST PATH I177
J 0
(-4575 1250);
DISPLAY 1.404255 (-4575 1250);
PAINT GREEN (-4575 1250);
DISPLAY INVISIBLE (-4575 1250);
FORCEPROP 2 LAST ROOM DDR4_CH_B
J 0
(-4650 1255);
PAINT ORANGE (-4650 1255);
DISPLAY INVISIBLE (-4650 1255);
FORCEPROP 1 LAST HDL_POWER GND
J 0
(-4650 1400);
DISPLAY 1.404255 (-4650 1400);
PAINT GREEN (-4650 1400);
DISPLAY INVISIBLE (-4650 1400);
FORCEADD PVPP_ABC..1
(-800 3000);
FORCEPROP 3 LASTPIN (-800 2950) SIG_NAME PVPP_ABC\g
J 0
(-790 2960);
DISPLAY 0.659574 (-790 2960);
PAINT MONO (-790 2960);
DISPLAY INVISIBLE (-790 2960);
FORCEPROP 1 LAST VOLTAGE 2.5V
J 0
(-845 2957);
DISPLAY 0.340426 (-845 2957);
PAINT SKYBLUE (-845 2957);
DISPLAY INVISIBLE (-845 2957);
FORCEPROP 2 LAST BOM_COST MEM
J 0
(-800 3005);
PAINT ORANGE (-800 3005);
DISPLAY INVISIBLE (-800 3005);
FORCEPROP 2 LAST CDS_LIB mstr_symbols
J 0
(-800 3000);
PAINT ORANGE (-800 3000);
DISPLAY INVISIBLE (-800 3000);
FORCEPROP 1 LAST BODY_TYPE PLUMBING
J 0
(-845 2957);
DISPLAY 0.340426 (-845 2957);
PAINT GREEN (-845 2957);
DISPLAY INVISIBLE (-845 2957);
FORCEPROP 1 LAST PATH I178
J 0
(-750 3025);
DISPLAY 0.872340 (-750 3025);
PAINT AQUA (-750 3025);
DISPLAY INVISIBLE (-750 3025);
FORCEPROP 2 LAST ROOM DDR4_CH_B
J 0
(-800 3005);
PAINT ORANGE (-800 3005);
DISPLAY INVISIBLE (-800 3005);
FORCEPROP 1 LAST HDL_POWER PVPP_ABC
J 1
(-800 3050);
DISPLAY 0.872340 (-800 3050);
PAINT GREEN (-800 3050);
DISPLAY INVISIBLE (-800 3050);
FORCEADD PVPP_ABC..1
(-4650 2250);
FORCEPROP 3 LASTPIN (-4650 2200) SIG_NAME PVPP_ABC\g
J 0
(-4640 2210);
DISPLAY 0.659574 (-4640 2210);
PAINT MONO (-4640 2210);
DISPLAY INVISIBLE (-4640 2210);
FORCEPROP 1 LAST VOLTAGE 2.5V
J 0
(-4695 2207);
DISPLAY 0.340426 (-4695 2207);
PAINT SKYBLUE (-4695 2207);
DISPLAY INVISIBLE (-4695 2207);
FORCEPROP 2 LAST BOM_COST MEM
J 0
(-4650 2255);
PAINT ORANGE (-4650 2255);
DISPLAY INVISIBLE (-4650 2255);
FORCEPROP 2 LAST CDS_LIB mstr_symbols
J 0
(-4650 2250);
PAINT ORANGE (-4650 2250);
DISPLAY INVISIBLE (-4650 2250);
FORCEPROP 1 LAST BODY_TYPE PLUMBING
J 0
(-4695 2207);
DISPLAY 0.340426 (-4695 2207);
PAINT GREEN (-4695 2207);
DISPLAY INVISIBLE (-4695 2207);
FORCEPROP 1 LAST PATH I179
J 0
(-4600 2275);
DISPLAY 0.872340 (-4600 2275);
PAINT AQUA (-4600 2275);
DISPLAY INVISIBLE (-4600 2275);
FORCEPROP 2 LAST ROOM DDR4_CH_B
J 0
(-4650 2255);
PAINT ORANGE (-4650 2255);
DISPLAY INVISIBLE (-4650 2255);
FORCEPROP 1 LAST HDL_POWER PVPP_ABC
J 1
(-4650 2300);
DISPLAY 0.872340 (-4650 2300);
PAINT GREEN (-4650 2300);
DISPLAY INVISIBLE (-4650 2300);
FORCEADD TAP..6
R 2
(700 4550);
FORCEPROP 3 LASTPIN (650 4550) SIG_NAME M_C_DQS_DP<11>
J 0
(660 4560);
DISPLAY 0.659574 (660 4560);
PAINT MONO (660 4560);
DISPLAY INVISIBLE (660 4560);
FORCEPROP 1 LASTPIN (650 4550) BN 11
J 2
(700 4560);
DISPLAY 0.617021 (700 4560);
PAINT PINK (700 4560);
FORCEPROP 2 LAST CDS_LIB mstr_standard
J 0
(700 4550);
DISPLAY 0.787234 (700 4550);
PAINT MONO (700 4550);
DISPLAY INVISIBLE (700 4550);
FORCEPROP 1 LAST BODY_TYPE PLUMBING
J 2
(700 4500);
DISPLAY 1.234043 (700 4500);
PAINT GREEN (700 4500);
DISPLAY INVISIBLE (700 4500);
FORCEPROP 1 LAST HDL_TAP TRUE
J 2
(375 4425);
DISPLAY 1.234043 (375 4425);
PAINT WHITE (375 4425);
DISPLAY INVISIBLE (375 4425);
FORCEPROP 1 LAST PATH I18
J 2
(700 4550);
DISPLAY 0.936170 (700 4550);
PAINT GREEN (700 4550);
DISPLAY INVISIBLE (700 4550);
FORCEADD OFFPAGE..1
(-3800 1400);
FORCEPROP 2 LAST $XR5 47 
J 0
(-4501 1400);
DISPLAY 0.638298 (-4501 1400);
PAINT MONO (-4501 1400);
FORCEPROP 2 LAST $XR4 46 
J 0
(-4411 1400);
DISPLAY 0.638298 (-4411 1400);
PAINT MONO (-4411 1400);
FORCEPROP 2 LAST $XR3 45 
J 0
(-4321 1400);
DISPLAY 0.638298 (-4321 1400);
PAINT MONO (-4321 1400);
FORCEPROP 2 LAST $XR2 44 
J 0
(-4231 1400);
DISPLAY 0.638298 (-4231 1400);
PAINT MONO (-4231 1400);
FORCEPROP 2 LAST $XR1 43 
J 0
(-4141 1400);
DISPLAY 0.638298 (-4141 1400);
PAINT MONO (-4141 1400);
FORCEPROP 2 LAST $XR0 89 
J 0
(-4051 1400);
DISPLAY 0.638298 (-4051 1400);
PAINT MONO (-4051 1400);
FORCEPROP 2 LAST CDS_LIB mstr_standard
J 0
(-3800 1400);
PAINT ORANGE (-3800 1400);
DISPLAY INVISIBLE (-3800 1400);
FORCEPROP 1 LAST OFFPAGE TRUE
J 0
(-3475 1275);
DISPLAY 0.936170 (-3475 1275);
PAINT GREEN (-3475 1275);
DISPLAY INVISIBLE (-3475 1275);
FORCEPROP 1 LAST COMMENT_BODY TRUE
J 0
(-3675 1300);
DISPLAY 0.936170 (-3675 1300);
PAINT GREEN (-3675 1300);
DISPLAY INVISIBLE (-3675 1300);
FORCEPROP 2 LAST PATH I180
J 0
(-3750 1475);
PAINT ORANGE (-3750 1475);
DISPLAY INVISIBLE (-3750 1475);
FORCEADD GND..1
(-4650 1850);
FORCEPROP 3 LASTPIN (-4650 1900) SIG_NAME GND\g
J 0
(-4640 1910);
DISPLAY 0.659574 (-4640 1910);
PAINT MONO (-4640 1910);
DISPLAY INVISIBLE (-4640 1910);
FORCEPROP 1 LAST VOLTAGE 0
J 0
(-4650 1850);
PAINT SKYBLUE (-4650 1850);
DISPLAY INVISIBLE (-4650 1850);
FORCEPROP 2 LAST CDS_LIB mstr_symbols
J 0
(-4650 1850);
PAINT ORANGE (-4650 1850);
DISPLAY INVISIBLE (-4650 1850);
FORCEPROP 2 LAST BOM_COST MEM
J 0
(-4650 1855);
PAINT ORANGE (-4650 1855);
DISPLAY INVISIBLE (-4650 1855);
FORCEPROP 1 LAST SIZE 1B
J 0
(-4575 1800);
DISPLAY 1.787234 (-4575 1800);
PAINT GREEN (-4575 1800);
DISPLAY INVISIBLE (-4575 1800);
FORCEPROP 1 LAST BODY_TYPE PLUMBING
J 0
(-4695 1807);
DISPLAY 0.340426 (-4695 1807);
PAINT GREEN (-4695 1807);
DISPLAY INVISIBLE (-4695 1807);
FORCEPROP 1 LAST PATH I184
J 0
(-4575 1850);
DISPLAY 0.872340 (-4575 1850);
PAINT AQUA (-4575 1850);
DISPLAY INVISIBLE (-4575 1850);
FORCEPROP 2 LAST ROOM DDR4_CH_B
J 0
(-4650 1855);
PAINT ORANGE (-4650 1855);
DISPLAY INVISIBLE (-4650 1855);
FORCEPROP 1 LAST HDL_POWER GND
J 0
(-4650 2000);
DISPLAY 1.404255 (-4650 2000);
PAINT GREEN (-4650 2000);
DISPLAY INVISIBLE (-4650 2000);
FORCEADD P12V_NVDIMM_ABC..1
(600 3075);
FORCEPROP 3 LASTPIN (600 3025) SIG_NAME P12V_NVDIMM_ABC\g
J 0
(610 3035);
DISPLAY 0.659574 (610 3035);
PAINT MONO (610 3035);
DISPLAY INVISIBLE (610 3035);
FORCEPROP 1 LAST VOLTAGE 12.0
J 0
(555 3032);
DISPLAY 0.340426 (555 3032);
PAINT SKYBLUE (555 3032);
DISPLAY INVISIBLE (555 3032);
FORCEPROP 2 LAST CDS_LIB mstr_symbols
J 0
(600 3075);
PAINT ORANGE (600 3075);
DISPLAY INVISIBLE (600 3075);
FORCEPROP 1 LAST BODY_TYPE PLUMBING
J 0
(555 3032);
DISPLAY 0.340426 (555 3032);
PAINT GREEN (555 3032);
DISPLAY INVISIBLE (555 3032);
FORCEPROP 1 LAST PATH I185
J 0
(650 3100);
DISPLAY 0.872340 (650 3100);
PAINT AQUA (650 3100);
DISPLAY INVISIBLE (650 3100);
FORCEPROP 1 LAST HDL_POWER P12V_NVDIMM_ABC
J 1
(600 3100);
DISPLAY 0.872340 (600 3100);
PAINT GREEN (600 3100);
DISPLAY INVISIBLE (600 3100);
FORCEADD TAP..6
R 2
(900 4400);
FORCEPROP 3 LASTPIN (850 4400) SIG_NAME M_C_DQS_DN<10>
J 0
(860 4410);
DISPLAY 0.659574 (860 4410);
PAINT MONO (860 4410);
DISPLAY INVISIBLE (860 4410);
FORCEPROP 1 LASTPIN (850 4400) BN 10
J 2
(900 4410);
DISPLAY 0.617021 (900 4410);
PAINT PINK (900 4410);
FORCEPROP 2 LAST CDS_LIB mstr_standard
J 0
(900 4400);
DISPLAY 0.787234 (900 4400);
PAINT MONO (900 4400);
DISPLAY INVISIBLE (900 4400);
FORCEPROP 1 LAST BODY_TYPE PLUMBING
J 2
(900 4350);
DISPLAY 1.234043 (900 4350);
PAINT GREEN (900 4350);
DISPLAY INVISIBLE (900 4350);
FORCEPROP 1 LAST HDL_TAP TRUE
J 2
(575 4275);
DISPLAY 1.234043 (575 4275);
PAINT GREEN (575 4275);
DISPLAY INVISIBLE (575 4275);
FORCEPROP 1 LAST PATH I19
J 2
(900 4400);
DISPLAY 0.936170 (900 4400);
PAINT GREEN (900 4400);
DISPLAY INVISIBLE (900 4400);
FORCEADD OFFPAGE..3
(1600 5150);
FORCEPROP 2 LAST $XR1 47 
J 0
(1904 5150);
DISPLAY 0.638298 (1904 5150);
PAINT MONO (1904 5150);
FORCEPROP 2 LAST $XR0 25 
J 0
(1814 5150);
DISPLAY 0.638298 (1814 5150);
PAINT MONO (1814 5150);
FORCEPROP 2 LAST CDS_LIB mstr_standard
J 0
(1600 5150);
DISPLAY 0.787234 (1600 5150);
PAINT MONO (1600 5150);
DISPLAY INVISIBLE (1600 5150);
FORCEPROP 1 LAST OFFPAGE TRUE
J 0
(1925 5025);
DISPLAY 0.936170 (1925 5025);
PAINT GREEN (1925 5025);
DISPLAY INVISIBLE (1925 5025);
FORCEPROP 1 LAST COMMENT_BODY TRUE
J 0
(1550 5050);
DISPLAY 0.936170 (1550 5050);
PAINT GREEN (1550 5050);
DISPLAY INVISIBLE (1550 5050);
FORCEPROP 2 LAST PATH I2
J 0
(1800 5225);
DISPLAY 0.787234 (1800 5225);
PAINT MONO (1800 5225);
DISPLAY INVISIBLE (1800 5225);
FORCEADD TAP..6
R 2
(900 4500);
FORCEPROP 3 LASTPIN (850 4500) SIG_NAME M_C_DQS_DN<11>
J 0
(860 4510);
DISPLAY 0.659574 (860 4510);
PAINT MONO (860 4510);
DISPLAY INVISIBLE (860 4510);
FORCEPROP 1 LASTPIN (850 4500) BN 11
J 2
(900 4510);
DISPLAY 0.617021 (900 4510);
PAINT PINK (900 4510);
FORCEPROP 2 LAST CDS_LIB mstr_standard
J 0
(900 4500);
DISPLAY 0.787234 (900 4500);
PAINT MONO (900 4500);
DISPLAY INVISIBLE (900 4500);
FORCEPROP 1 LAST BODY_TYPE PLUMBING
J 2
(900 4450);
DISPLAY 1.234043 (900 4450);
PAINT GREEN (900 4450);
DISPLAY INVISIBLE (900 4450);
FORCEPROP 1 LAST HDL_TAP TRUE
J 2
(575 4375);
DISPLAY 1.234043 (575 4375);
PAINT GREEN (575 4375);
DISPLAY INVISIBLE (575 4375);
FORCEPROP 1 LAST PATH I20
J 2
(900 4500);
DISPLAY 0.936170 (900 4500);
PAINT GREEN (900 4500);
DISPLAY INVISIBLE (900 4500);
FORCEADD TAP..6
R 2
(900 4300);
FORCEPROP 3 LASTPIN (850 4300) SIG_NAME M_C_DQS_DN<9>
J 0
(860 4310);
DISPLAY 0.659574 (860 4310);
PAINT MONO (860 4310);
DISPLAY INVISIBLE (860 4310);
FORCEPROP 1 LASTPIN (850 4300) BN 9
J 2
(900 4310);
DISPLAY 0.617021 (900 4310);
PAINT PINK (900 4310);
FORCEPROP 2 LAST CDS_LIB mstr_standard
J 0
(900 4300);
DISPLAY 0.787234 (900 4300);
PAINT MONO (900 4300);
DISPLAY INVISIBLE (900 4300);
FORCEPROP 1 LAST BODY_TYPE PLUMBING
J 2
(900 4250);
DISPLAY 1.234043 (900 4250);
PAINT GREEN (900 4250);
DISPLAY INVISIBLE (900 4250);
FORCEPROP 1 LAST HDL_TAP TRUE
J 2
(575 4175);
DISPLAY 1.234043 (575 4175);
PAINT GREEN (575 4175);
DISPLAY INVISIBLE (575 4175);
FORCEPROP 1 LAST PATH I21
J 2
(900 4300);
DISPLAY 0.936170 (900 4300);
PAINT GREEN (900 4300);
DISPLAY INVISIBLE (900 4300);
FORCEADD TAP..6
R 2
(700 4450);
FORCEPROP 3 LASTPIN (650 4450) SIG_NAME M_C_DQS_DP<10>
J 0
(660 4460);
DISPLAY 0.659574 (660 4460);
PAINT MONO (660 4460);
DISPLAY INVISIBLE (660 4460);
FORCEPROP 1 LASTPIN (650 4450) BN 10
J 2
(700 4460);
DISPLAY 0.617021 (700 4460);
PAINT PINK (700 4460);
FORCEPROP 2 LAST CDS_LIB mstr_standard
J 0
(700 4450);
DISPLAY 0.787234 (700 4450);
PAINT MONO (700 4450);
DISPLAY INVISIBLE (700 4450);
FORCEPROP 1 LAST BODY_TYPE PLUMBING
J 2
(700 4400);
DISPLAY 1.234043 (700 4400);
PAINT GREEN (700 4400);
DISPLAY INVISIBLE (700 4400);
FORCEPROP 1 LAST HDL_TAP TRUE
J 2
(375 4325);
DISPLAY 1.234043 (375 4325);
PAINT WHITE (375 4325);
DISPLAY INVISIBLE (375 4325);
FORCEPROP 1 LAST PATH I22
J 2
(700 4450);
DISPLAY 0.936170 (700 4450);
PAINT GREEN (700 4450);
DISPLAY INVISIBLE (700 4450);
FORCEADD TAP..6
R 2
(700 4350);
FORCEPROP 3 LASTPIN (650 4350) SIG_NAME M_C_DQS_DP<9>
J 0
(660 4360);
DISPLAY 0.659574 (660 4360);
PAINT MONO (660 4360);
DISPLAY INVISIBLE (660 4360);
FORCEPROP 1 LASTPIN (650 4350) BN 9
J 2
(700 4360);
DISPLAY 0.617021 (700 4360);
PAINT PINK (700 4360);
FORCEPROP 2 LAST CDS_LIB mstr_standard
J 0
(700 4350);
DISPLAY 0.787234 (700 4350);
PAINT MONO (700 4350);
DISPLAY INVISIBLE (700 4350);
FORCEPROP 1 LAST BODY_TYPE PLUMBING
J 2
(700 4300);
DISPLAY 1.234043 (700 4300);
PAINT GREEN (700 4300);
DISPLAY INVISIBLE (700 4300);
FORCEPROP 1 LAST HDL_TAP TRUE
J 2
(375 4225);
DISPLAY 1.234043 (375 4225);
PAINT WHITE (375 4225);
DISPLAY INVISIBLE (375 4225);
FORCEPROP 1 LAST PATH I23
J 2
(700 4350);
DISPLAY 0.936170 (700 4350);
PAINT GREEN (700 4350);
DISPLAY INVISIBLE (700 4350);
FORCEADD TAP..6
R 2
(900 4100);
FORCEPROP 3 LASTPIN (850 4100) SIG_NAME M_C_DQS_DN<7>
J 0
(860 4110);
DISPLAY 0.659574 (860 4110);
PAINT MONO (860 4110);
DISPLAY INVISIBLE (860 4110);
FORCEPROP 1 LASTPIN (850 4100) BN 7
J 2
(900 4110);
DISPLAY 0.617021 (900 4110);
PAINT PINK (900 4110);
FORCEPROP 2 LAST CDS_LIB mstr_standard
J 0
(900 4100);
DISPLAY 0.787234 (900 4100);
PAINT MONO (900 4100);
DISPLAY INVISIBLE (900 4100);
FORCEPROP 1 LAST BODY_TYPE PLUMBING
J 2
(900 4050);
DISPLAY 1.234043 (900 4050);
PAINT GREEN (900 4050);
DISPLAY INVISIBLE (900 4050);
FORCEPROP 1 LAST HDL_TAP TRUE
J 2
(575 3975);
DISPLAY 1.234043 (575 3975);
PAINT GREEN (575 3975);
DISPLAY INVISIBLE (575 3975);
FORCEPROP 1 LAST PATH I24
J 2
(900 4100);
DISPLAY 0.936170 (900 4100);
PAINT GREEN (900 4100);
DISPLAY INVISIBLE (900 4100);
FORCEADD TAP..6
R 2
(900 4200);
FORCEPROP 3 LASTPIN (850 4200) SIG_NAME M_C_DQS_DN<8>
J 0
(860 4210);
DISPLAY 0.659574 (860 4210);
PAINT MONO (860 4210);
DISPLAY INVISIBLE (860 4210);
FORCEPROP 1 LASTPIN (850 4200) BN 8
J 2
(900 4210);
DISPLAY 0.617021 (900 4210);
PAINT PINK (900 4210);
FORCEPROP 2 LAST CDS_LIB mstr_standard
J 0
(900 4200);
DISPLAY 0.787234 (900 4200);
PAINT MONO (900 4200);
DISPLAY INVISIBLE (900 4200);
FORCEPROP 1 LAST BODY_TYPE PLUMBING
J 2
(900 4150);
DISPLAY 1.234043 (900 4150);
PAINT GREEN (900 4150);
DISPLAY INVISIBLE (900 4150);
FORCEPROP 1 LAST HDL_TAP TRUE
J 2
(575 4075);
DISPLAY 1.234043 (575 4075);
PAINT GREEN (575 4075);
DISPLAY INVISIBLE (575 4075);
FORCEPROP 1 LAST PATH I25
J 2
(900 4200);
DISPLAY 0.936170 (900 4200);
PAINT GREEN (900 4200);
DISPLAY INVISIBLE (900 4200);
FORCEADD TAP..6
R 2
(700 4250);
FORCEPROP 3 LASTPIN (650 4250) SIG_NAME M_C_DQS_DP<8>
J 0
(660 4260);
DISPLAY 0.659574 (660 4260);
PAINT MONO (660 4260);
DISPLAY INVISIBLE (660 4260);
FORCEPROP 1 LASTPIN (650 4250) BN 8
J 2
(700 4260);
DISPLAY 0.617021 (700 4260);
PAINT PINK (700 4260);
FORCEPROP 2 LAST CDS_LIB mstr_standard
J 0
(700 4250);
DISPLAY 0.787234 (700 4250);
PAINT MONO (700 4250);
DISPLAY INVISIBLE (700 4250);
FORCEPROP 1 LAST BODY_TYPE PLUMBING
J 2
(700 4200);
DISPLAY 1.234043 (700 4200);
PAINT GREEN (700 4200);
DISPLAY INVISIBLE (700 4200);
FORCEPROP 1 LAST HDL_TAP TRUE
J 2
(375 4125);
DISPLAY 1.234043 (375 4125);
PAINT WHITE (375 4125);
DISPLAY INVISIBLE (375 4125);
FORCEPROP 1 LAST PATH I26
J 2
(700 4250);
DISPLAY 0.936170 (700 4250);
PAINT GREEN (700 4250);
DISPLAY INVISIBLE (700 4250);
FORCEADD TAP..6
R 2
(700 4150);
FORCEPROP 3 LASTPIN (650 4150) SIG_NAME M_C_DQS_DP<7>
J 0
(660 4160);
DISPLAY 0.659574 (660 4160);
PAINT MONO (660 4160);
DISPLAY INVISIBLE (660 4160);
FORCEPROP 1 LASTPIN (650 4150) BN 7
J 2
(700 4160);
DISPLAY 0.617021 (700 4160);
PAINT PINK (700 4160);
FORCEPROP 2 LAST CDS_LIB mstr_standard
J 0
(700 4150);
DISPLAY 0.787234 (700 4150);
PAINT MONO (700 4150);
DISPLAY INVISIBLE (700 4150);
FORCEPROP 1 LAST BODY_TYPE PLUMBING
J 2
(700 4100);
DISPLAY 1.234043 (700 4100);
PAINT GREEN (700 4100);
DISPLAY INVISIBLE (700 4100);
FORCEPROP 1 LAST HDL_TAP TRUE
J 2
(375 4025);
DISPLAY 1.234043 (375 4025);
PAINT WHITE (375 4025);
DISPLAY INVISIBLE (375 4025);
FORCEPROP 1 LAST PATH I27
J 2
(700 4150);
DISPLAY 0.936170 (700 4150);
PAINT GREEN (700 4150);
DISPLAY INVISIBLE (700 4150);
FORCEADD TAP..6
R 2
(700 4050);
FORCEPROP 3 LASTPIN (650 4050) SIG_NAME M_C_DQS_DP<6>
J 0
(660 4060);
DISPLAY 0.659574 (660 4060);
PAINT MONO (660 4060);
DISPLAY INVISIBLE (660 4060);
FORCEPROP 1 LASTPIN (650 4050) BN 6
J 2
(700 4060);
DISPLAY 0.617021 (700 4060);
PAINT PINK (700 4060);
FORCEPROP 2 LAST CDS_LIB mstr_standard
J 0
(700 4050);
DISPLAY 0.787234 (700 4050);
PAINT MONO (700 4050);
DISPLAY INVISIBLE (700 4050);
FORCEPROP 1 LAST BODY_TYPE PLUMBING
J 2
(700 4000);
DISPLAY 1.234043 (700 4000);
PAINT GREEN (700 4000);
DISPLAY INVISIBLE (700 4000);
FORCEPROP 1 LAST HDL_TAP TRUE
J 2
(375 3925);
DISPLAY 1.234043 (375 3925);
PAINT WHITE (375 3925);
DISPLAY INVISIBLE (375 3925);
FORCEPROP 1 LAST PATH I28
J 2
(700 4050);
DISPLAY 0.936170 (700 4050);
PAINT GREEN (700 4050);
DISPLAY INVISIBLE (700 4050);
FORCEADD TAP..6
R 2
(900 3900);
FORCEPROP 3 LASTPIN (850 3900) SIG_NAME M_C_DQS_DN<5>
J 0
(860 3910);
DISPLAY 0.659574 (860 3910);
PAINT MONO (860 3910);
DISPLAY INVISIBLE (860 3910);
FORCEPROP 1 LASTPIN (850 3900) BN 5
J 2
(900 3910);
DISPLAY 0.617021 (900 3910);
PAINT PINK (900 3910);
FORCEPROP 2 LAST CDS_LIB mstr_standard
J 0
(900 3900);
DISPLAY 0.787234 (900 3900);
PAINT MONO (900 3900);
DISPLAY INVISIBLE (900 3900);
FORCEPROP 1 LAST BODY_TYPE PLUMBING
J 2
(900 3850);
DISPLAY 1.234043 (900 3850);
PAINT GREEN (900 3850);
DISPLAY INVISIBLE (900 3850);
FORCEPROP 1 LAST HDL_TAP TRUE
J 2
(575 3775);
DISPLAY 1.234043 (575 3775);
PAINT GREEN (575 3775);
DISPLAY INVISIBLE (575 3775);
FORCEPROP 1 LAST PATH I29
J 2
(900 3900);
DISPLAY 0.936170 (900 3900);
PAINT GREEN (900 3900);
DISPLAY INVISIBLE (900 3900);
FORCEADD TAP..6
R 2
(900 5100);
FORCEPROP 3 LASTPIN (850 5100) SIG_NAME M_C_DQS_DN<17>
J 0
(860 5110);
DISPLAY 0.659574 (860 5110);
PAINT MONO (860 5110);
DISPLAY INVISIBLE (860 5110);
FORCEPROP 1 LASTPIN (850 5100) BN 17
J 2
(900 5110);
DISPLAY 0.617021 (900 5110);
PAINT PINK (900 5110);
FORCEPROP 2 LAST CDS_LIB mstr_standard
J 2
(900 5100);
DISPLAY 0.787234 (900 5100);
PAINT MONO (900 5100);
DISPLAY INVISIBLE (900 5100);
FORCEPROP 1 LAST BODY_TYPE PLUMBING
J 2
(900 5050);
DISPLAY 1.234043 (900 5050);
PAINT GREEN (900 5050);
DISPLAY INVISIBLE (900 5050);
FORCEPROP 1 LAST HDL_TAP TRUE
J 2
(575 4975);
DISPLAY 1.234043 (575 4975);
PAINT GREEN (575 4975);
DISPLAY INVISIBLE (575 4975);
FORCEPROP 1 LAST PATH I3
J 2
(900 5100);
DISPLAY 0.936170 (900 5100);
PAINT GREEN (900 5100);
DISPLAY INVISIBLE (900 5100);
FORCEADD TAP..6
R 2
(900 4000);
FORCEPROP 3 LASTPIN (850 4000) SIG_NAME M_C_DQS_DN<6>
J 0
(860 4010);
DISPLAY 0.659574 (860 4010);
PAINT MONO (860 4010);
DISPLAY INVISIBLE (860 4010);
FORCEPROP 1 LASTPIN (850 4000) BN 6
J 2
(900 4010);
DISPLAY 0.617021 (900 4010);
PAINT PINK (900 4010);
FORCEPROP 2 LAST CDS_LIB mstr_standard
J 0
(900 4000);
DISPLAY 0.787234 (900 4000);
PAINT MONO (900 4000);
DISPLAY INVISIBLE (900 4000);
FORCEPROP 1 LAST BODY_TYPE PLUMBING
J 2
(900 3950);
DISPLAY 1.234043 (900 3950);
PAINT GREEN (900 3950);
DISPLAY INVISIBLE (900 3950);
FORCEPROP 1 LAST HDL_TAP TRUE
J 2
(575 3875);
DISPLAY 1.234043 (575 3875);
PAINT GREEN (575 3875);
DISPLAY INVISIBLE (575 3875);
FORCEPROP 1 LAST PATH I30
J 2
(900 4000);
DISPLAY 0.936170 (900 4000);
PAINT GREEN (900 4000);
DISPLAY INVISIBLE (900 4000);
FORCEADD TAP..6
R 2
(900 3800);
FORCEPROP 3 LASTPIN (850 3800) SIG_NAME M_C_DQS_DN<4>
J 0
(860 3810);
DISPLAY 0.659574 (860 3810);
PAINT MONO (860 3810);
DISPLAY INVISIBLE (860 3810);
FORCEPROP 1 LASTPIN (850 3800) BN 4
J 2
(900 3810);
DISPLAY 0.617021 (900 3810);
PAINT PINK (900 3810);
FORCEPROP 2 LAST CDS_LIB mstr_standard
J 0
(900 3800);
DISPLAY 0.787234 (900 3800);
PAINT MONO (900 3800);
DISPLAY INVISIBLE (900 3800);
FORCEPROP 1 LAST BODY_TYPE PLUMBING
J 2
(900 3750);
DISPLAY 1.234043 (900 3750);
PAINT GREEN (900 3750);
DISPLAY INVISIBLE (900 3750);
FORCEPROP 1 LAST HDL_TAP TRUE
J 2
(575 3675);
DISPLAY 1.234043 (575 3675);
PAINT GREEN (575 3675);
DISPLAY INVISIBLE (575 3675);
FORCEPROP 1 LAST PATH I31
J 2
(900 3800);
DISPLAY 0.936170 (900 3800);
PAINT GREEN (900 3800);
DISPLAY INVISIBLE (900 3800);
FORCEADD TAP..6
R 2
(700 3950);
FORCEPROP 3 LASTPIN (650 3950) SIG_NAME M_C_DQS_DP<5>
J 0
(660 3960);
DISPLAY 0.659574 (660 3960);
PAINT MONO (660 3960);
DISPLAY INVISIBLE (660 3960);
FORCEPROP 1 LASTPIN (650 3950) BN 5
J 2
(700 3960);
DISPLAY 0.617021 (700 3960);
PAINT PINK (700 3960);
FORCEPROP 2 LAST CDS_LIB mstr_standard
J 0
(700 3950);
DISPLAY 0.787234 (700 3950);
PAINT MONO (700 3950);
DISPLAY INVISIBLE (700 3950);
FORCEPROP 1 LAST BODY_TYPE PLUMBING
J 2
(700 3900);
DISPLAY 1.234043 (700 3900);
PAINT GREEN (700 3900);
DISPLAY INVISIBLE (700 3900);
FORCEPROP 1 LAST HDL_TAP TRUE
J 2
(375 3825);
DISPLAY 1.234043 (375 3825);
PAINT WHITE (375 3825);
DISPLAY INVISIBLE (375 3825);
FORCEPROP 1 LAST PATH I32
J 2
(700 3950);
DISPLAY 0.936170 (700 3950);
PAINT GREEN (700 3950);
DISPLAY INVISIBLE (700 3950);
FORCEADD TAP..6
R 2
(700 3850);
FORCEPROP 3 LASTPIN (650 3850) SIG_NAME M_C_DQS_DP<4>
J 0
(660 3860);
DISPLAY 0.659574 (660 3860);
PAINT MONO (660 3860);
DISPLAY INVISIBLE (660 3860);
FORCEPROP 1 LASTPIN (650 3850) BN 4
J 2
(700 3860);
DISPLAY 0.617021 (700 3860);
PAINT PINK (700 3860);
FORCEPROP 2 LAST CDS_LIB mstr_standard
J 0
(700 3850);
DISPLAY 0.787234 (700 3850);
PAINT MONO (700 3850);
DISPLAY INVISIBLE (700 3850);
FORCEPROP 1 LAST BODY_TYPE PLUMBING
J 2
(700 3800);
DISPLAY 1.234043 (700 3800);
PAINT GREEN (700 3800);
DISPLAY INVISIBLE (700 3800);
FORCEPROP 1 LAST HDL_TAP TRUE
J 2
(375 3725);
DISPLAY 1.234043 (375 3725);
PAINT WHITE (375 3725);
DISPLAY INVISIBLE (375 3725);
FORCEPROP 1 LAST PATH I33
J 2
(700 3850);
DISPLAY 0.936170 (700 3850);
PAINT GREEN (700 3850);
DISPLAY INVISIBLE (700 3850);
FORCEADD TAP..6
R 2
(700 3750);
FORCEPROP 3 LASTPIN (650 3750) SIG_NAME M_C_DQS_DP<3>
J 0
(660 3760);
DISPLAY 0.659574 (660 3760);
PAINT MONO (660 3760);
DISPLAY INVISIBLE (660 3760);
FORCEPROP 1 LASTPIN (650 3750) BN 3
J 2
(700 3760);
DISPLAY 0.617021 (700 3760);
PAINT PINK (700 3760);
FORCEPROP 2 LAST CDS_LIB mstr_standard
J 0
(700 3750);
DISPLAY 0.787234 (700 3750);
PAINT MONO (700 3750);
DISPLAY INVISIBLE (700 3750);
FORCEPROP 1 LAST BODY_TYPE PLUMBING
J 2
(700 3700);
DISPLAY 1.234043 (700 3700);
PAINT GREEN (700 3700);
DISPLAY INVISIBLE (700 3700);
FORCEPROP 1 LAST HDL_TAP TRUE
J 2
(375 3625);
DISPLAY 1.234043 (375 3625);
PAINT WHITE (375 3625);
DISPLAY INVISIBLE (375 3625);
FORCEPROP 1 LAST PATH I34
J 2
(700 3750);
DISPLAY 0.936170 (700 3750);
PAINT GREEN (700 3750);
DISPLAY INVISIBLE (700 3750);
FORCEADD TAP..6
R 2
(900 3500);
FORCEPROP 3 LASTPIN (850 3500) SIG_NAME M_C_DQS_DN<1>
J 0
(860 3510);
DISPLAY 0.659574 (860 3510);
PAINT MONO (860 3510);
DISPLAY INVISIBLE (860 3510);
FORCEPROP 1 LASTPIN (850 3500) BN 1
J 2
(900 3510);
DISPLAY 0.617021 (900 3510);
PAINT PINK (900 3510);
FORCEPROP 2 LAST CDS_LIB mstr_standard
J 0
(900 3500);
DISPLAY 0.787234 (900 3500);
PAINT MONO (900 3500);
DISPLAY INVISIBLE (900 3500);
FORCEPROP 1 LAST BODY_TYPE PLUMBING
J 2
(900 3450);
DISPLAY 1.234043 (900 3450);
PAINT GREEN (900 3450);
DISPLAY INVISIBLE (900 3450);
FORCEPROP 1 LAST HDL_TAP TRUE
J 2
(575 3375);
DISPLAY 1.234043 (575 3375);
PAINT GREEN (575 3375);
DISPLAY INVISIBLE (575 3375);
FORCEPROP 1 LAST PATH I35
J 2
(900 3500);
DISPLAY 0.936170 (900 3500);
PAINT GREEN (900 3500);
DISPLAY INVISIBLE (900 3500);
FORCEADD TAP..6
R 2
(900 3600);
FORCEPROP 3 LASTPIN (850 3600) SIG_NAME M_C_DQS_DN<2>
J 0
(860 3610);
DISPLAY 0.659574 (860 3610);
PAINT MONO (860 3610);
DISPLAY INVISIBLE (860 3610);
FORCEPROP 1 LASTPIN (850 3600) BN 2
J 2
(900 3610);
DISPLAY 0.617021 (900 3610);
PAINT PINK (900 3610);
FORCEPROP 2 LAST CDS_LIB mstr_standard
J 0
(900 3600);
DISPLAY 0.787234 (900 3600);
PAINT MONO (900 3600);
DISPLAY INVISIBLE (900 3600);
FORCEPROP 1 LAST BODY_TYPE PLUMBING
J 2
(900 3550);
DISPLAY 1.234043 (900 3550);
PAINT GREEN (900 3550);
DISPLAY INVISIBLE (900 3550);
FORCEPROP 1 LAST HDL_TAP TRUE
J 2
(575 3475);
DISPLAY 1.234043 (575 3475);
PAINT GREEN (575 3475);
DISPLAY INVISIBLE (575 3475);
FORCEPROP 1 LAST PATH I36
J 2
(900 3600);
DISPLAY 0.936170 (900 3600);
PAINT GREEN (900 3600);
DISPLAY INVISIBLE (900 3600);
FORCEADD TAP..6
R 2
(900 3700);
FORCEPROP 3 LASTPIN (850 3700) SIG_NAME M_C_DQS_DN<3>
J 0
(860 3710);
DISPLAY 0.659574 (860 3710);
PAINT MONO (860 3710);
DISPLAY INVISIBLE (860 3710);
FORCEPROP 1 LASTPIN (850 3700) BN 3
J 2
(900 3710);
DISPLAY 0.617021 (900 3710);
PAINT PINK (900 3710);
FORCEPROP 2 LAST CDS_LIB mstr_standard
J 0
(900 3700);
DISPLAY 0.787234 (900 3700);
PAINT MONO (900 3700);
DISPLAY INVISIBLE (900 3700);
FORCEPROP 1 LAST BODY_TYPE PLUMBING
J 2
(900 3650);
DISPLAY 1.234043 (900 3650);
PAINT GREEN (900 3650);
DISPLAY INVISIBLE (900 3650);
FORCEPROP 1 LAST HDL_TAP TRUE
J 2
(575 3575);
DISPLAY 1.234043 (575 3575);
PAINT GREEN (575 3575);
DISPLAY INVISIBLE (575 3575);
FORCEPROP 1 LAST PATH I37
J 2
(900 3700);
DISPLAY 0.936170 (900 3700);
PAINT GREEN (900 3700);
DISPLAY INVISIBLE (900 3700);
FORCEADD TAP..6
R 2
(700 3650);
FORCEPROP 3 LASTPIN (650 3650) SIG_NAME M_C_DQS_DP<2>
J 0
(660 3660);
DISPLAY 0.659574 (660 3660);
PAINT MONO (660 3660);
DISPLAY INVISIBLE (660 3660);
FORCEPROP 1 LASTPIN (650 3650) BN 2
J 2
(700 3660);
DISPLAY 0.617021 (700 3660);
PAINT PINK (700 3660);
FORCEPROP 2 LAST CDS_LIB mstr_standard
J 0
(700 3650);
DISPLAY 0.787234 (700 3650);
PAINT MONO (700 3650);
DISPLAY INVISIBLE (700 3650);
FORCEPROP 1 LAST BODY_TYPE PLUMBING
J 2
(700 3600);
DISPLAY 1.234043 (700 3600);
PAINT GREEN (700 3600);
DISPLAY INVISIBLE (700 3600);
FORCEPROP 1 LAST HDL_TAP TRUE
J 2
(375 3525);
DISPLAY 1.234043 (375 3525);
PAINT WHITE (375 3525);
DISPLAY INVISIBLE (375 3525);
FORCEPROP 1 LAST PATH I38
J 2
(700 3650);
DISPLAY 0.936170 (700 3650);
PAINT GREEN (700 3650);
DISPLAY INVISIBLE (700 3650);
FORCEADD TAP..6
R 2
(700 3550);
FORCEPROP 3 LASTPIN (650 3550) SIG_NAME M_C_DQS_DP<1>
J 0
(660 3560);
DISPLAY 0.659574 (660 3560);
PAINT MONO (660 3560);
DISPLAY INVISIBLE (660 3560);
FORCEPROP 1 LASTPIN (650 3550) BN 1
J 2
(700 3560);
DISPLAY 0.617021 (700 3560);
PAINT PINK (700 3560);
FORCEPROP 2 LAST CDS_LIB mstr_standard
J 0
(700 3550);
DISPLAY 0.787234 (700 3550);
PAINT MONO (700 3550);
DISPLAY INVISIBLE (700 3550);
FORCEPROP 1 LAST BODY_TYPE PLUMBING
J 2
(700 3500);
DISPLAY 1.234043 (700 3500);
PAINT GREEN (700 3500);
DISPLAY INVISIBLE (700 3500);
FORCEPROP 1 LAST HDL_TAP TRUE
J 2
(375 3425);
DISPLAY 1.234043 (375 3425);
PAINT WHITE (375 3425);
DISPLAY INVISIBLE (375 3425);
FORCEPROP 1 LAST PATH I39
J 2
(700 3550);
DISPLAY 0.936170 (700 3550);
PAINT GREEN (700 3550);
DISPLAY INVISIBLE (700 3550);
FORCEADD TAP..6
R 2
(700 5150);
FORCEPROP 3 LASTPIN (650 5150) SIG_NAME M_C_DQS_DP<17>
J 0
(660 5160);
DISPLAY 0.659574 (660 5160);
PAINT MONO (660 5160);
DISPLAY INVISIBLE (660 5160);
FORCEPROP 1 LASTPIN (650 5150) BN 17
J 2
(700 5160);
DISPLAY 0.617021 (700 5160);
PAINT PINK (700 5160);
FORCEPROP 2 LAST CDS_LIB mstr_standard
J 2
(700 5150);
DISPLAY 0.787234 (700 5150);
PAINT MONO (700 5150);
DISPLAY INVISIBLE (700 5150);
FORCEPROP 1 LAST BODY_TYPE PLUMBING
J 2
(700 5100);
DISPLAY 1.234043 (700 5100);
PAINT GREEN (700 5100);
DISPLAY INVISIBLE (700 5100);
FORCEPROP 1 LAST HDL_TAP TRUE
J 2
(375 5025);
DISPLAY 1.234043 (375 5025);
PAINT WHITE (375 5025);
DISPLAY INVISIBLE (375 5025);
FORCEPROP 1 LAST PATH I4
J 2
(700 5150);
DISPLAY 0.936170 (700 5150);
PAINT GREEN (700 5150);
DISPLAY INVISIBLE (700 5150);
FORCEADD TAP..6
R 2
(900 3400);
FORCEPROP 3 LASTPIN (850 3400) SIG_NAME M_C_DQS_DN<0>
J 0
(860 3410);
DISPLAY 0.659574 (860 3410);
PAINT MONO (860 3410);
DISPLAY INVISIBLE (860 3410);
FORCEPROP 1 LASTPIN (850 3400) BN 0
J 2
(900 3410);
DISPLAY 0.617021 (900 3410);
PAINT PINK (900 3410);
FORCEPROP 2 LAST CDS_LIB mstr_standard
J 0
(900 3400);
DISPLAY 0.787234 (900 3400);
PAINT MONO (900 3400);
DISPLAY INVISIBLE (900 3400);
FORCEPROP 1 LAST BODY_TYPE PLUMBING
J 2
(900 3350);
DISPLAY 1.234043 (900 3350);
PAINT GREEN (900 3350);
DISPLAY INVISIBLE (900 3350);
FORCEPROP 1 LAST HDL_TAP TRUE
J 2
(575 3275);
DISPLAY 1.234043 (575 3275);
PAINT GREEN (575 3275);
DISPLAY INVISIBLE (575 3275);
FORCEPROP 1 LAST PATH I40
J 2
(900 3400);
DISPLAY 0.936170 (900 3400);
PAINT GREEN (900 3400);
DISPLAY INVISIBLE (900 3400);
FORCEADD TAP..6
R 2
(700 3450);
FORCEPROP 3 LASTPIN (650 3450) SIG_NAME M_C_DQS_DP<0>
J 0
(660 3460);
DISPLAY 0.659574 (660 3460);
PAINT MONO (660 3460);
DISPLAY INVISIBLE (660 3460);
FORCEPROP 1 LASTPIN (650 3450) BN 0
J 2
(700 3460);
DISPLAY 0.617021 (700 3460);
PAINT PINK (700 3460);
FORCEPROP 2 LAST CDS_LIB mstr_standard
J 0
(700 3450);
DISPLAY 0.787234 (700 3450);
PAINT MONO (700 3450);
DISPLAY INVISIBLE (700 3450);
FORCEPROP 1 LAST BODY_TYPE PLUMBING
J 2
(700 3400);
DISPLAY 1.234043 (700 3400);
PAINT GREEN (700 3400);
DISPLAY INVISIBLE (700 3400);
FORCEPROP 1 LAST HDL_TAP TRUE
J 2
(375 3325);
DISPLAY 1.234043 (375 3325);
PAINT WHITE (375 3325);
DISPLAY INVISIBLE (375 3325);
FORCEPROP 1 LAST PATH I41
J 2
(700 3450);
DISPLAY 0.936170 (700 3450);
PAINT GREEN (700 3450);
DISPLAY INVISIBLE (700 3450);
FORCEADD SCONN288_H44441003..3
(1800 2600);
FORCEPROP 1 LAST LOCATION J6U2
J 0
(1350 4000);
DISPLAY 0.617021 (1350 4000);
PAINT AQUA (1350 4000);
FORCEPROP 1 LAST PART_NUMBER H44441-003
J 0
(1350 1250);
DISPLAY 0.617021 (1350 1250);
PAINT BLUE (1350 1250);
FORCEPROP 1 LAST MATERIAL SCONN
J 0
(1350 3950);
DISPLAY 0.617021 (1350 3950);
PAINT SKYBLUE (1350 3950);
FORCEPROP 2 LASTPIN (1300 3750) $PN 2
J 2
(1290 3760);
DISPLAY 0.617021 (1290 3760);
PAINT ORANGE (1290 3760);
FORCEPROP 2 LASTPIN (1300 3700) $PN 4
J 2
(1290 3710);
DISPLAY 0.617021 (1290 3710);
PAINT ORANGE (1290 3710);
FORCEPROP 2 LASTPIN (1300 3650) $PN 6
J 2
(1290 3660);
DISPLAY 0.617021 (1290 3660);
PAINT ORANGE (1290 3660);
FORCEPROP 2 LASTPIN (1300 3600) $PN 9
J 2
(1290 3610);
DISPLAY 0.617021 (1290 3610);
PAINT ORANGE (1290 3610);
FORCEPROP 2 LASTPIN (1300 3550) $PN 11
J 2
(1290 3560);
DISPLAY 0.617021 (1290 3560);
PAINT ORANGE (1290 3560);
FORCEPROP 2 LASTPIN (1300 3500) $PN 13
J 2
(1290 3510);
DISPLAY 0.617021 (1290 3510);
PAINT ORANGE (1290 3510);
FORCEPROP 2 LASTPIN (1300 3450) $PN 15
J 2
(1290 3460);
DISPLAY 0.617021 (1290 3460);
PAINT ORANGE (1290 3460);
FORCEPROP 2 LASTPIN (1300 3400) $PN 17
J 2
(1290 3410);
DISPLAY 0.617021 (1290 3410);
PAINT ORANGE (1290 3410);
FORCEPROP 2 LASTPIN (1300 3350) $PN 20
J 2
(1290 3360);
DISPLAY 0.617021 (1290 3360);
PAINT ORANGE (1290 3360);
FORCEPROP 2 LASTPIN (1300 3300) $PN 22
J 2
(1290 3310);
DISPLAY 0.617021 (1290 3310);
PAINT ORANGE (1290 3310);
FORCEPROP 2 LASTPIN (1300 3250) $PN 24
J 2
(1290 3260);
DISPLAY 0.617021 (1290 3260);
PAINT ORANGE (1290 3260);
FORCEPROP 2 LASTPIN (1300 3200) $PN 26
J 2
(1290 3210);
DISPLAY 0.617021 (1290 3210);
PAINT ORANGE (1290 3210);
FORCEPROP 2 LASTPIN (1300 3150) $PN 28
J 2
(1290 3160);
DISPLAY 0.617021 (1290 3160);
PAINT ORANGE (1290 3160);
FORCEPROP 2 LASTPIN (1300 3100) $PN 31
J 2
(1290 3110);
DISPLAY 0.617021 (1290 3110);
PAINT ORANGE (1290 3110);
FORCEPROP 2 LASTPIN (1300 3050) $PN 33
J 2
(1290 3060);
DISPLAY 0.617021 (1290 3060);
PAINT ORANGE (1290 3060);
FORCEPROP 2 LASTPIN (1300 3000) $PN 35
J 2
(1290 3010);
DISPLAY 0.617021 (1290 3010);
PAINT ORANGE (1290 3010);
FORCEPROP 2 LASTPIN (1300 2950) $PN 37
J 2
(1290 2960);
DISPLAY 0.617021 (1290 2960);
PAINT ORANGE (1290 2960);
FORCEPROP 2 LASTPIN (1300 2900) $PN 39
J 2
(1290 2910);
DISPLAY 0.617021 (1290 2910);
PAINT ORANGE (1290 2910);
FORCEPROP 2 LASTPIN (1300 2850) $PN 42
J 2
(1290 2860);
DISPLAY 0.617021 (1290 2860);
PAINT ORANGE (1290 2860);
FORCEPROP 2 LASTPIN (1300 2800) $PN 44
J 2
(1290 2810);
DISPLAY 0.617021 (1290 2810);
PAINT ORANGE (1290 2810);
FORCEPROP 2 LASTPIN (1300 2750) $PN 46
J 2
(1290 2760);
DISPLAY 0.617021 (1290 2760);
PAINT ORANGE (1290 2760);
FORCEPROP 2 LASTPIN (1300 2700) $PN 48
J 2
(1290 2710);
DISPLAY 0.617021 (1290 2710);
PAINT ORANGE (1290 2710);
FORCEPROP 2 LASTPIN (1300 2650) $PN 50
J 2
(1290 2660);
DISPLAY 0.617021 (1290 2660);
PAINT ORANGE (1290 2660);
FORCEPROP 2 LASTPIN (1300 2600) $PN 53
J 2
(1290 2610);
DISPLAY 0.617021 (1290 2610);
PAINT ORANGE (1290 2610);
FORCEPROP 2 LASTPIN (1300 2550) $PN 55
J 2
(1290 2560);
DISPLAY 0.617021 (1290 2560);
PAINT ORANGE (1290 2560);
FORCEPROP 2 LASTPIN (1300 2500) $PN 57
J 2
(1290 2510);
DISPLAY 0.617021 (1290 2510);
PAINT ORANGE (1290 2510);
FORCEPROP 2 LASTPIN (1300 2450) $PN 94
J 2
(1290 2460);
DISPLAY 0.617021 (1290 2460);
PAINT ORANGE (1290 2460);
FORCEPROP 2 LASTPIN (1300 2400) $PN 96
J 2
(1290 2410);
DISPLAY 0.617021 (1290 2410);
PAINT ORANGE (1290 2410);
FORCEPROP 2 LASTPIN (1300 2350) $PN 98
J 2
(1290 2360);
DISPLAY 0.617021 (1290 2360);
PAINT ORANGE (1290 2360);
FORCEPROP 2 LASTPIN (1300 2300) $PN 101
J 2
(1290 2310);
DISPLAY 0.617021 (1290 2310);
PAINT ORANGE (1290 2310);
FORCEPROP 2 LASTPIN (1300 2250) $PN 103
J 2
(1290 2260);
DISPLAY 0.617021 (1290 2260);
PAINT ORANGE (1290 2260);
FORCEPROP 2 LASTPIN (1300 2200) $PN 105
J 2
(1290 2210);
DISPLAY 0.617021 (1290 2210);
PAINT ORANGE (1290 2210);
FORCEPROP 2 LASTPIN (1300 2150) $PN 107
J 2
(1290 2160);
DISPLAY 0.617021 (1290 2160);
PAINT ORANGE (1290 2160);
FORCEPROP 2 LASTPIN (1300 2100) $PN 109
J 2
(1290 2110);
DISPLAY 0.617021 (1290 2110);
PAINT ORANGE (1290 2110);
FORCEPROP 2 LASTPIN (1300 2050) $PN 112
J 2
(1290 2060);
DISPLAY 0.617021 (1290 2060);
PAINT ORANGE (1290 2060);
FORCEPROP 2 LASTPIN (1300 2000) $PN 114
J 2
(1290 2010);
DISPLAY 0.617021 (1290 2010);
PAINT ORANGE (1290 2010);
FORCEPROP 2 LASTPIN (1300 1900) $PN 118
J 2
(1290 1910);
DISPLAY 0.617021 (1290 1910);
PAINT ORANGE (1290 1910);
FORCEPROP 2 LASTPIN (1300 1850) $PN 120
J 2
(1290 1860);
DISPLAY 0.617021 (1290 1860);
PAINT ORANGE (1290 1860);
FORCEPROP 2 LASTPIN (1300 1800) $PN 123
J 2
(1290 1810);
DISPLAY 0.617021 (1290 1810);
PAINT ORANGE (1290 1810);
FORCEPROP 2 LASTPIN (1300 1750) $PN 125
J 2
(1290 1760);
DISPLAY 0.617021 (1290 1760);
PAINT ORANGE (1290 1760);
FORCEPROP 2 LASTPIN (1300 1700) $PN 127
J 2
(1290 1710);
DISPLAY 0.617021 (1290 1710);
PAINT ORANGE (1290 1710);
FORCEPROP 2 LASTPIN (1300 1650) $PN 129
J 2
(1290 1660);
DISPLAY 0.617021 (1290 1660);
PAINT ORANGE (1290 1660);
FORCEPROP 2 LASTPIN (1300 1600) $PN 131
J 2
(1290 1610);
DISPLAY 0.617021 (1290 1610);
PAINT ORANGE (1290 1610);
FORCEPROP 2 LASTPIN (1300 1550) $PN 134
J 2
(1290 1560);
DISPLAY 0.617021 (1290 1560);
PAINT ORANGE (1290 1560);
FORCEPROP 2 LASTPIN (1300 1450) $PN 138
J 2
(1290 1460);
DISPLAY 0.617021 (1290 1460);
PAINT ORANGE (1290 1460);
FORCEPROP 2 LASTPIN (2300 3750) $PN 147
J 0
(2310 3760);
DISPLAY 0.617021 (2310 3760);
PAINT ORANGE (2310 3760);
FORCEPROP 2 LASTPIN (2300 3700) $PN 149
J 0
(2310 3710);
DISPLAY 0.617021 (2310 3710);
PAINT ORANGE (2310 3710);
FORCEPROP 2 LASTPIN (2300 3650) $PN 151
J 0
(2310 3660);
DISPLAY 0.617021 (2310 3660);
PAINT ORANGE (2310 3660);
FORCEPROP 2 LASTPIN (2300 3600) $PN 154
J 0
(2310 3610);
DISPLAY 0.617021 (2310 3610);
PAINT ORANGE (2310 3610);
FORCEPROP 2 LASTPIN (2300 3550) $PN 156
J 0
(2310 3560);
DISPLAY 0.617021 (2310 3560);
PAINT ORANGE (2310 3560);
FORCEPROP 2 LASTPIN (2300 3500) $PN 158
J 0
(2310 3510);
DISPLAY 0.617021 (2310 3510);
PAINT ORANGE (2310 3510);
FORCEPROP 2 LASTPIN (2300 3450) $PN 160
J 0
(2310 3460);
DISPLAY 0.617021 (2310 3460);
PAINT ORANGE (2310 3460);
FORCEPROP 2 LASTPIN (2300 3400) $PN 162
J 0
(2310 3410);
DISPLAY 0.617021 (2310 3410);
PAINT ORANGE (2310 3410);
FORCEPROP 2 LASTPIN (2300 3300) $PN 167
J 0
(2310 3310);
DISPLAY 0.617021 (2310 3310);
PAINT ORANGE (2310 3310);
FORCEPROP 2 LASTPIN (2300 3250) $PN 169
J 0
(2310 3260);
DISPLAY 0.617021 (2310 3260);
PAINT ORANGE (2310 3260);
FORCEPROP 2 LASTPIN (2300 3200) $PN 171
J 0
(2310 3210);
DISPLAY 0.617021 (2310 3210);
PAINT ORANGE (2310 3210);
FORCEPROP 2 LASTPIN (2300 3150) $PN 173
J 0
(2310 3160);
DISPLAY 0.617021 (2310 3160);
PAINT ORANGE (2310 3160);
FORCEPROP 2 LASTPIN (2300 3100) $PN 176
J 0
(2310 3110);
DISPLAY 0.617021 (2310 3110);
PAINT ORANGE (2310 3110);
FORCEPROP 2 LASTPIN (2300 3050) $PN 178
J 0
(2310 3060);
DISPLAY 0.617021 (2310 3060);
PAINT ORANGE (2310 3060);
FORCEPROP 2 LASTPIN (2300 3000) $PN 180
J 0
(2310 3010);
DISPLAY 0.617021 (2310 3010);
PAINT ORANGE (2310 3010);
FORCEPROP 2 LASTPIN (2300 2950) $PN 182
J 0
(2310 2960);
DISPLAY 0.617021 (2310 2960);
PAINT ORANGE (2310 2960);
FORCEPROP 2 LASTPIN (2300 2900) $PN 184
J 0
(2310 2910);
DISPLAY 0.617021 (2310 2910);
PAINT ORANGE (2310 2910);
FORCEPROP 2 LASTPIN (2300 2850) $PN 187
J 0
(2310 2860);
DISPLAY 0.617021 (2310 2860);
PAINT ORANGE (2310 2860);
FORCEPROP 2 LASTPIN (2300 2800) $PN 189
J 0
(2310 2810);
DISPLAY 0.617021 (2310 2810);
PAINT ORANGE (2310 2810);
FORCEPROP 2 LASTPIN (2300 2750) $PN 191
J 0
(2310 2760);
DISPLAY 0.617021 (2310 2760);
PAINT ORANGE (2310 2760);
FORCEPROP 2 LASTPIN (2300 2700) $PN 193
J 0
(2310 2710);
DISPLAY 0.617021 (2310 2710);
PAINT ORANGE (2310 2710);
FORCEPROP 2 LASTPIN (2300 2650) $PN 195
J 0
(2310 2660);
DISPLAY 0.617021 (2310 2660);
PAINT ORANGE (2310 2660);
FORCEPROP 2 LASTPIN (2300 2600) $PN 198
J 0
(2310 2610);
DISPLAY 0.617021 (2310 2610);
PAINT ORANGE (2310 2610);
FORCEPROP 2 LASTPIN (2300 2550) $PN 200
J 0
(2310 2560);
DISPLAY 0.617021 (2310 2560);
PAINT ORANGE (2310 2560);
FORCEPROP 2 LASTPIN (2300 2500) $PN 202
J 0
(2310 2510);
DISPLAY 0.617021 (2310 2510);
PAINT ORANGE (2310 2510);
FORCEPROP 2 LASTPIN (2300 2450) $PN 239
J 0
(2310 2460);
DISPLAY 0.617021 (2310 2460);
PAINT ORANGE (2310 2460);
FORCEPROP 2 LASTPIN (2300 2400) $PN 241
J 0
(2310 2410);
DISPLAY 0.617021 (2310 2410);
PAINT ORANGE (2310 2410);
FORCEPROP 2 LASTPIN (2300 2350) $PN 243
J 0
(2310 2360);
DISPLAY 0.617021 (2310 2360);
PAINT ORANGE (2310 2360);
FORCEPROP 2 LASTPIN (2300 2300) $PN 246
J 0
(2310 2310);
DISPLAY 0.617021 (2310 2310);
PAINT ORANGE (2310 2310);
FORCEPROP 2 LASTPIN (2300 2250) $PN 248
J 0
(2310 2260);
DISPLAY 0.617021 (2310 2260);
PAINT ORANGE (2310 2260);
FORCEPROP 2 LASTPIN (2300 2200) $PN 250
J 0
(2310 2210);
DISPLAY 0.617021 (2310 2210);
PAINT ORANGE (2310 2210);
FORCEPROP 2 LASTPIN (2300 2150) $PN 252
J 0
(2310 2160);
DISPLAY 0.617021 (2310 2160);
PAINT ORANGE (2310 2160);
FORCEPROP 2 LASTPIN (2300 2100) $PN 254
J 0
(2310 2110);
DISPLAY 0.617021 (2310 2110);
PAINT ORANGE (2310 2110);
FORCEPROP 2 LASTPIN (2300 2050) $PN 257
J 0
(2310 2060);
DISPLAY 0.617021 (2310 2060);
PAINT ORANGE (2310 2060);
FORCEPROP 2 LASTPIN (2300 2000) $PN 259
J 0
(2310 2010);
DISPLAY 0.617021 (2310 2010);
PAINT ORANGE (2310 2010);
FORCEPROP 2 LASTPIN (2300 1950) $PN 261
J 0
(2310 1960);
DISPLAY 0.617021 (2310 1960);
PAINT ORANGE (2310 1960);
FORCEPROP 2 LASTPIN (2300 1900) $PN 263
J 0
(2310 1910);
DISPLAY 0.617021 (2310 1910);
PAINT ORANGE (2310 1910);
FORCEPROP 2 LASTPIN (2300 1850) $PN 265
J 0
(2310 1860);
DISPLAY 0.617021 (2310 1860);
PAINT ORANGE (2310 1860);
FORCEPROP 2 LASTPIN (2300 1800) $PN 268
J 0
(2310 1810);
DISPLAY 0.617021 (2310 1810);
PAINT ORANGE (2310 1810);
FORCEPROP 2 LASTPIN (2300 1750) $PN 270
J 0
(2310 1760);
DISPLAY 0.617021 (2310 1760);
PAINT ORANGE (2310 1760);
FORCEPROP 2 LASTPIN (2300 1700) $PN 272
J 0
(2310 1710);
DISPLAY 0.617021 (2310 1710);
PAINT ORANGE (2310 1710);
FORCEPROP 2 LASTPIN (2300 1650) $PN 274
J 0
(2310 1660);
DISPLAY 0.617021 (2310 1660);
PAINT ORANGE (2310 1660);
FORCEPROP 2 LASTPIN (2300 1600) $PN 276
J 0
(2310 1610);
DISPLAY 0.617021 (2310 1610);
PAINT ORANGE (2310 1610);
FORCEPROP 2 LASTPIN (2300 1550) $PN 279
J 0
(2310 1560);
DISPLAY 0.617021 (2310 1560);
PAINT ORANGE (2310 1560);
FORCEPROP 2 LASTPIN (2300 1500) $PN 281
J 0
(2310 1510);
DISPLAY 0.617021 (2310 1510);
PAINT ORANGE (2310 1510);
FORCEPROP 2 LASTPIN (2300 1450) $PN 283
J 0
(2310 1460);
DISPLAY 0.617021 (2310 1460);
PAINT ORANGE (2310 1460);
FORCEPROP 2 LASTPIN (1300 1950) $PN 116
J 2
(1290 1960);
DISPLAY 0.617021 (1290 1960);
PAINT ORANGE (1290 1960);
FORCEPROP 0 LAST BOM_SS NOPOP
J 0
(1546 3959);
DISPLAY 1.021277 (1546 3959);
PAINT BROWN (1546 3959);
DISPLAY BOTH (1546 3959);
FORCEPROP 2 LASTPIN (2300 3350) $PN 165
J 0
(2310 3360);
DISPLAY 0.617021 (2310 3360);
PAINT ORANGE (2310 3360);
FORCEPROP 2 LASTPIN (1300 1500) $PN 136
J 2
(1290 1510);
DISPLAY 0.617021 (1290 1510);
PAINT ORANGE (1290 1510);
FORCEPROP 1 LAST PACK_TYPE PIP
J 0
(1350 4050);
PAINT SKYBLUE (1350 4050);
DISPLAY INVISIBLE (1350 4050);
FORCEPROP 2 LAST BOM_COST MEM
J 0
(1800 2600);
PAINT ORANGE (1800 2600);
DISPLAY INVISIBLE (1800 2600);
FORCEPROP 2 LAST CDS_LIB mstr_sconn
J 0
(1800 2600);
PAINT ORANGE (1800 2600);
DISPLAY INVISIBLE (1800 2600);
FORCEPROP 2 LAST SEC_TYPE PIP
J 0
(1350 4050);
DISPLAY 1.021277 (1350 4050);
PAINT ORANGE (1350 4050);
DISPLAY INVISIBLE (1350 4050);
FORCEPROP 2 LAST SEC 3
J 0
(1350 4050);
DISPLAY 0.680851 (1350 4050);
PAINT MONO (1350 4050);
DISPLAY INVISIBLE (1350 4050);
FORCEPROP 2 LAST CDS_LOCATION J6U2
J 0
(1350 4000);
DISPLAY 0.617021 (1350 4000);
PAINT AQUA (1350 4000);
DISPLAY INVISIBLE (1350 4000);
FORCEPROP 1 LAST PATH I43
J 0
(1800 3950);
PAINT GREEN (1800 3950);
DISPLAY INVISIBLE (1800 3950);
FORCEPROP 2 LAST ROOM DDR4_CH_C1
J 0
(1800 2600);
PAINT ORANGE (1800 2600);
DISPLAY INVISIBLE (1800 2600);
FORCEADD GND..1
R 2
(1100 1300);
FORCEPROP 3 LASTPIN (1100 1350) SIG_NAME GND\g
J 0
(1110 1360);
DISPLAY 0.659574 (1110 1360);
PAINT MONO (1110 1360);
DISPLAY INVISIBLE (1110 1360);
FORCEPROP 1 LAST VOLTAGE 0
J 0
(1100 1300);
PAINT SKYBLUE (1100 1300);
DISPLAY INVISIBLE (1100 1300);
FORCEPROP 2 LAST CDS_LIB mstr_symbols
J 0
(1100 1300);
DISPLAY 0.787234 (1100 1300);
PAINT MONO (1100 1300);
DISPLAY INVISIBLE (1100 1300);
FORCEPROP 1 LAST SIZE 1B
J 2
(1025 1250);
DISPLAY 1.170213 (1025 1250);
PAINT GREEN (1025 1250);
DISPLAY INVISIBLE (1025 1250);
FORCEPROP 2 LAST BOM_COST MEM
J 0
(1100 1305);
PAINT ORANGE (1100 1305);
DISPLAY INVISIBLE (1100 1305);
FORCEPROP 1 LAST BODY_TYPE PLUMBING
J 2
(1145 1257);
DISPLAY 0.340426 (1145 1257);
PAINT GREEN (1145 1257);
DISPLAY INVISIBLE (1145 1257);
FORCEPROP 1 LAST PATH I44
J 2
(1025 1300);
DISPLAY 0.936170 (1025 1300);
PAINT GREEN (1025 1300);
DISPLAY INVISIBLE (1025 1300);
FORCEPROP 2 LAST ROOM DDR4_CH_B
J 0
(1100 1305);
PAINT ORANGE (1100 1305);
DISPLAY INVISIBLE (1100 1305);
FORCEPROP 1 LAST HDL_POWER GND
J 2
(1100 1450);
DISPLAY 0.553191 (1100 1450);
PAINT GREEN (1100 1450);
DISPLAY INVISIBLE (1100 1450);
FORCEADD OFFPAGE..3
(-1100 4900);
FORCEPROP 2 LAST $XR1 47 
J 0
(-796 4900);
DISPLAY 0.638298 (-796 4900);
PAINT MONO (-796 4900);
FORCEPROP 2 LAST $XR0 25 
J 0
(-886 4900);
DISPLAY 0.638298 (-886 4900);
PAINT MONO (-886 4900);
FORCEPROP 2 LAST CDS_LIB mstr_standard
J 0
(-1100 4900);
DISPLAY 0.787234 (-1100 4900);
PAINT MONO (-1100 4900);
DISPLAY INVISIBLE (-1100 4900);
FORCEPROP 1 LAST OFFPAGE TRUE
J 0
(-775 4775);
DISPLAY 0.936170 (-775 4775);
PAINT GREEN (-775 4775);
DISPLAY INVISIBLE (-775 4775);
FORCEPROP 1 LAST COMMENT_BODY TRUE
J 0
(-1150 4800);
DISPLAY 0.936170 (-1150 4800);
PAINT GREEN (-1150 4800);
DISPLAY INVISIBLE (-1150 4800);
FORCEPROP 2 LAST PATH I45
J 0
(-900 4975);
DISPLAY 0.787234 (-900 4975);
PAINT MONO (-900 4975);
DISPLAY INVISIBLE (-900 4975);
FORCEADD TAP..6
R 2
(-1650 4850);
FORCEPROP 3 LASTPIN (-1700 4850) SIG_NAME M_C_DQ<63>
J 0
(-1690 4860);
DISPLAY 0.659574 (-1690 4860);
PAINT MONO (-1690 4860);
DISPLAY INVISIBLE (-1690 4860);
FORCEPROP 1 LASTPIN (-1700 4850) BN 63
J 2
(-1650 4860);
DISPLAY 0.617021 (-1650 4860);
PAINT PINK (-1650 4860);
FORCEPROP 2 LAST CDS_LIB mstr_standard
J 2
(-1650 4850);
DISPLAY 0.787234 (-1650 4850);
PAINT MONO (-1650 4850);
DISPLAY INVISIBLE (-1650 4850);
FORCEPROP 1 LAST BODY_TYPE PLUMBING
J 2
(-1650 4800);
DISPLAY 1.234043 (-1650 4800);
PAINT GREEN (-1650 4800);
DISPLAY INVISIBLE (-1650 4800);
FORCEPROP 1 LAST HDL_TAP TRUE
J 2
(-1975 4725);
DISPLAY 1.234043 (-1975 4725);
PAINT GREEN (-1975 4725);
DISPLAY INVISIBLE (-1975 4725);
FORCEPROP 1 LAST PATH I46
J 2
(-1650 4850);
DISPLAY 0.936170 (-1650 4850);
PAINT GREEN (-1650 4850);
DISPLAY INVISIBLE (-1650 4850);
FORCEADD TAP..6
R 2
(-1650 4800);
FORCEPROP 3 LASTPIN (-1700 4800) SIG_NAME M_C_DQ<62>
J 0
(-1690 4810);
DISPLAY 0.659574 (-1690 4810);
PAINT MONO (-1690 4810);
DISPLAY INVISIBLE (-1690 4810);
FORCEPROP 1 LASTPIN (-1700 4800) BN 62
J 2
(-1650 4810);
DISPLAY 0.617021 (-1650 4810);
PAINT PINK (-1650 4810);
FORCEPROP 2 LAST CDS_LIB mstr_standard
J 2
(-1650 4800);
DISPLAY 0.787234 (-1650 4800);
PAINT MONO (-1650 4800);
DISPLAY INVISIBLE (-1650 4800);
FORCEPROP 1 LAST BODY_TYPE PLUMBING
J 2
(-1650 4750);
DISPLAY 1.234043 (-1650 4750);
PAINT GREEN (-1650 4750);
DISPLAY INVISIBLE (-1650 4750);
FORCEPROP 1 LAST HDL_TAP TRUE
J 2
(-1975 4675);
DISPLAY 1.234043 (-1975 4675);
PAINT GREEN (-1975 4675);
DISPLAY INVISIBLE (-1975 4675);
FORCEPROP 1 LAST PATH I47
J 2
(-1650 4800);
DISPLAY 0.936170 (-1650 4800);
PAINT GREEN (-1650 4800);
DISPLAY INVISIBLE (-1650 4800);
FORCEADD TAP..6
R 2
(-1650 4650);
FORCEPROP 3 LASTPIN (-1700 4650) SIG_NAME M_C_DQ<59>
J 0
(-1690 4660);
DISPLAY 0.659574 (-1690 4660);
PAINT MONO (-1690 4660);
DISPLAY INVISIBLE (-1690 4660);
FORCEPROP 1 LASTPIN (-1700 4650) BN 59
J 2
(-1650 4660);
DISPLAY 0.617021 (-1650 4660);
PAINT PINK (-1650 4660);
FORCEPROP 2 LAST CDS_LIB mstr_standard
J 2
(-1650 4650);
DISPLAY 0.787234 (-1650 4650);
PAINT MONO (-1650 4650);
DISPLAY INVISIBLE (-1650 4650);
FORCEPROP 1 LAST BODY_TYPE PLUMBING
J 2
(-1650 4600);
DISPLAY 1.234043 (-1650 4600);
PAINT GREEN (-1650 4600);
DISPLAY INVISIBLE (-1650 4600);
FORCEPROP 1 LAST HDL_TAP TRUE
J 2
(-1975 4525);
DISPLAY 1.234043 (-1975 4525);
PAINT GREEN (-1975 4525);
DISPLAY INVISIBLE (-1975 4525);
FORCEPROP 1 LAST PATH I48
J 2
(-1650 4650);
DISPLAY 0.936170 (-1650 4650);
PAINT GREEN (-1650 4650);
DISPLAY INVISIBLE (-1650 4650);
FORCEADD TAP..6
R 2
(-1650 4700);
FORCEPROP 3 LASTPIN (-1700 4700) SIG_NAME M_C_DQ<60>
J 0
(-1690 4710);
DISPLAY 0.659574 (-1690 4710);
PAINT MONO (-1690 4710);
DISPLAY INVISIBLE (-1690 4710);
FORCEPROP 1 LASTPIN (-1700 4700) BN 60
J 2
(-1650 4710);
DISPLAY 0.617021 (-1650 4710);
PAINT PINK (-1650 4710);
FORCEPROP 2 LAST CDS_LIB mstr_standard
J 2
(-1650 4700);
DISPLAY 0.787234 (-1650 4700);
PAINT MONO (-1650 4700);
DISPLAY INVISIBLE (-1650 4700);
FORCEPROP 1 LAST BODY_TYPE PLUMBING
J 2
(-1650 4650);
DISPLAY 1.234043 (-1650 4650);
PAINT GREEN (-1650 4650);
DISPLAY INVISIBLE (-1650 4650);
FORCEPROP 1 LAST HDL_TAP TRUE
J 2
(-1975 4575);
DISPLAY 1.234043 (-1975 4575);
PAINT GREEN (-1975 4575);
DISPLAY INVISIBLE (-1975 4575);
FORCEPROP 1 LAST PATH I49
J 2
(-1650 4700);
DISPLAY 0.936170 (-1650 4700);
PAINT GREEN (-1650 4700);
DISPLAY INVISIBLE (-1650 4700);
FORCEADD TAP..6
R 2
(700 5050);
FORCEPROP 3 LASTPIN (650 5050) SIG_NAME M_C_DQS_DP<16>
J 0
(660 5060);
DISPLAY 0.659574 (660 5060);
PAINT MONO (660 5060);
DISPLAY INVISIBLE (660 5060);
FORCEPROP 1 LASTPIN (650 5050) BN 16
J 2
(700 5060);
DISPLAY 0.617021 (700 5060);
PAINT PINK (700 5060);
FORCEPROP 2 LAST CDS_LIB mstr_standard
J 0
(700 5050);
DISPLAY 0.787234 (700 5050);
PAINT MONO (700 5050);
DISPLAY INVISIBLE (700 5050);
FORCEPROP 1 LAST BODY_TYPE PLUMBING
J 2
(700 5000);
DISPLAY 1.234043 (700 5000);
PAINT GREEN (700 5000);
DISPLAY INVISIBLE (700 5000);
FORCEPROP 1 LAST HDL_TAP TRUE
J 2
(375 4925);
DISPLAY 1.234043 (375 4925);
PAINT WHITE (375 4925);
DISPLAY INVISIBLE (375 4925);
FORCEPROP 1 LAST PATH I5
J 2
(700 5050);
DISPLAY 0.936170 (700 5050);
PAINT GREEN (700 5050);
DISPLAY INVISIBLE (700 5050);
FORCEADD TAP..6
R 2
(-1650 4750);
FORCEPROP 3 LASTPIN (-1700 4750) SIG_NAME M_C_DQ<61>
J 0
(-1690 4760);
DISPLAY 0.659574 (-1690 4760);
PAINT MONO (-1690 4760);
DISPLAY INVISIBLE (-1690 4760);
FORCEPROP 1 LASTPIN (-1700 4750) BN 61
J 2
(-1650 4760);
DISPLAY 0.617021 (-1650 4760);
PAINT PINK (-1650 4760);
FORCEPROP 2 LAST CDS_LIB mstr_standard
J 2
(-1650 4750);
DISPLAY 0.787234 (-1650 4750);
PAINT MONO (-1650 4750);
DISPLAY INVISIBLE (-1650 4750);
FORCEPROP 1 LAST BODY_TYPE PLUMBING
J 2
(-1650 4700);
DISPLAY 1.234043 (-1650 4700);
PAINT GREEN (-1650 4700);
DISPLAY INVISIBLE (-1650 4700);
FORCEPROP 1 LAST HDL_TAP TRUE
J 2
(-1975 4625);
DISPLAY 1.234043 (-1975 4625);
PAINT GREEN (-1975 4625);
DISPLAY INVISIBLE (-1975 4625);
FORCEPROP 1 LAST PATH I50
J 2
(-1650 4750);
DISPLAY 0.936170 (-1650 4750);
PAINT GREEN (-1650 4750);
DISPLAY INVISIBLE (-1650 4750);
FORCEADD TAP..6
R 2
(-1650 4550);
FORCEPROP 3 LASTPIN (-1700 4550) SIG_NAME M_C_DQ<57>
J 0
(-1690 4560);
DISPLAY 0.659574 (-1690 4560);
PAINT MONO (-1690 4560);
DISPLAY INVISIBLE (-1690 4560);
FORCEPROP 1 LASTPIN (-1700 4550) BN 57
J 2
(-1650 4560);
DISPLAY 0.617021 (-1650 4560);
PAINT PINK (-1650 4560);
FORCEPROP 2 LAST CDS_LIB mstr_standard
J 2
(-1650 4550);
DISPLAY 0.787234 (-1650 4550);
PAINT MONO (-1650 4550);
DISPLAY INVISIBLE (-1650 4550);
FORCEPROP 1 LAST BODY_TYPE PLUMBING
J 2
(-1650 4500);
DISPLAY 1.234043 (-1650 4500);
PAINT GREEN (-1650 4500);
DISPLAY INVISIBLE (-1650 4500);
FORCEPROP 1 LAST HDL_TAP TRUE
J 2
(-1975 4425);
DISPLAY 1.234043 (-1975 4425);
PAINT GREEN (-1975 4425);
DISPLAY INVISIBLE (-1975 4425);
FORCEPROP 1 LAST PATH I51
J 2
(-1650 4550);
DISPLAY 0.936170 (-1650 4550);
PAINT GREEN (-1650 4550);
DISPLAY INVISIBLE (-1650 4550);
FORCEADD TAP..6
R 2
(-1650 4600);
FORCEPROP 3 LASTPIN (-1700 4600) SIG_NAME M_C_DQ<58>
J 0
(-1690 4610);
DISPLAY 0.659574 (-1690 4610);
PAINT MONO (-1690 4610);
DISPLAY INVISIBLE (-1690 4610);
FORCEPROP 1 LASTPIN (-1700 4600) BN 58
J 2
(-1650 4610);
DISPLAY 0.617021 (-1650 4610);
PAINT PINK (-1650 4610);
FORCEPROP 2 LAST CDS_LIB mstr_standard
J 2
(-1650 4600);
DISPLAY 0.787234 (-1650 4600);
PAINT MONO (-1650 4600);
DISPLAY INVISIBLE (-1650 4600);
FORCEPROP 1 LAST BODY_TYPE PLUMBING
J 2
(-1650 4550);
DISPLAY 1.234043 (-1650 4550);
PAINT GREEN (-1650 4550);
DISPLAY INVISIBLE (-1650 4550);
FORCEPROP 1 LAST HDL_TAP TRUE
J 2
(-1975 4475);
DISPLAY 1.234043 (-1975 4475);
PAINT GREEN (-1975 4475);
DISPLAY INVISIBLE (-1975 4475);
FORCEPROP 1 LAST PATH I52
J 2
(-1650 4600);
DISPLAY 0.936170 (-1650 4600);
PAINT GREEN (-1650 4600);
DISPLAY INVISIBLE (-1650 4600);
FORCEADD TAP..6
R 2
(-1650 4400);
FORCEPROP 3 LASTPIN (-1700 4400) SIG_NAME M_C_DQ<54>
J 0
(-1690 4410);
DISPLAY 0.659574 (-1690 4410);
PAINT MONO (-1690 4410);
DISPLAY INVISIBLE (-1690 4410);
FORCEPROP 1 LASTPIN (-1700 4400) BN 54
J 2
(-1650 4410);
DISPLAY 0.617021 (-1650 4410);
PAINT PINK (-1650 4410);
FORCEPROP 2 LAST CDS_LIB mstr_standard
J 2
(-1650 4400);
DISPLAY 0.787234 (-1650 4400);
PAINT MONO (-1650 4400);
DISPLAY INVISIBLE (-1650 4400);
FORCEPROP 1 LAST BODY_TYPE PLUMBING
J 2
(-1650 4350);
DISPLAY 1.234043 (-1650 4350);
PAINT GREEN (-1650 4350);
DISPLAY INVISIBLE (-1650 4350);
FORCEPROP 1 LAST HDL_TAP TRUE
J 2
(-1975 4275);
DISPLAY 1.234043 (-1975 4275);
PAINT GREEN (-1975 4275);
DISPLAY INVISIBLE (-1975 4275);
FORCEPROP 1 LAST PATH I53
J 2
(-1650 4400);
DISPLAY 0.936170 (-1650 4400);
PAINT GREEN (-1650 4400);
DISPLAY INVISIBLE (-1650 4400);
FORCEADD TAP..6
R 2
(-1650 4450);
FORCEPROP 3 LASTPIN (-1700 4450) SIG_NAME M_C_DQ<55>
J 0
(-1690 4460);
DISPLAY 0.659574 (-1690 4460);
PAINT MONO (-1690 4460);
DISPLAY INVISIBLE (-1690 4460);
FORCEPROP 1 LASTPIN (-1700 4450) BN 55
J 2
(-1650 4460);
DISPLAY 0.617021 (-1650 4460);
PAINT PINK (-1650 4460);
FORCEPROP 2 LAST CDS_LIB mstr_standard
J 2
(-1650 4450);
DISPLAY 0.787234 (-1650 4450);
PAINT MONO (-1650 4450);
DISPLAY INVISIBLE (-1650 4450);
FORCEPROP 1 LAST BODY_TYPE PLUMBING
J 2
(-1650 4400);
DISPLAY 1.234043 (-1650 4400);
PAINT GREEN (-1650 4400);
DISPLAY INVISIBLE (-1650 4400);
FORCEPROP 1 LAST HDL_TAP TRUE
J 2
(-1975 4325);
DISPLAY 1.234043 (-1975 4325);
PAINT GREEN (-1975 4325);
DISPLAY INVISIBLE (-1975 4325);
FORCEPROP 1 LAST PATH I54
J 2
(-1650 4450);
DISPLAY 0.936170 (-1650 4450);
PAINT GREEN (-1650 4450);
DISPLAY INVISIBLE (-1650 4450);
FORCEADD TAP..6
R 2
(-1650 4500);
FORCEPROP 3 LASTPIN (-1700 4500) SIG_NAME M_C_DQ<56>
J 0
(-1690 4510);
DISPLAY 0.659574 (-1690 4510);
PAINT MONO (-1690 4510);
DISPLAY INVISIBLE (-1690 4510);
FORCEPROP 1 LASTPIN (-1700 4500) BN 56
J 2
(-1650 4510);
DISPLAY 0.617021 (-1650 4510);
PAINT PINK (-1650 4510);
FORCEPROP 2 LAST CDS_LIB mstr_standard
J 2
(-1650 4500);
DISPLAY 0.787234 (-1650 4500);
PAINT MONO (-1650 4500);
DISPLAY INVISIBLE (-1650 4500);
FORCEPROP 1 LAST BODY_TYPE PLUMBING
J 2
(-1650 4450);
DISPLAY 1.234043 (-1650 4450);
PAINT GREEN (-1650 4450);
DISPLAY INVISIBLE (-1650 4450);
FORCEPROP 1 LAST HDL_TAP TRUE
J 2
(-1975 4375);
DISPLAY 1.234043 (-1975 4375);
PAINT GREEN (-1975 4375);
DISPLAY INVISIBLE (-1975 4375);
FORCEPROP 1 LAST PATH I55
J 2
(-1650 4500);
DISPLAY 0.936170 (-1650 4500);
PAINT GREEN (-1650 4500);
DISPLAY INVISIBLE (-1650 4500);
FORCEADD TAP..6
R 2
(-1650 4300);
FORCEPROP 3 LASTPIN (-1700 4300) SIG_NAME M_C_DQ<52>
J 0
(-1690 4310);
DISPLAY 0.659574 (-1690 4310);
PAINT MONO (-1690 4310);
DISPLAY INVISIBLE (-1690 4310);
FORCEPROP 1 LASTPIN (-1700 4300) BN 52
J 2
(-1650 4310);
DISPLAY 0.617021 (-1650 4310);
PAINT PINK (-1650 4310);
FORCEPROP 2 LAST CDS_LIB mstr_standard
J 2
(-1650 4300);
DISPLAY 0.787234 (-1650 4300);
PAINT MONO (-1650 4300);
DISPLAY INVISIBLE (-1650 4300);
FORCEPROP 1 LAST BODY_TYPE PLUMBING
J 2
(-1650 4250);
DISPLAY 1.234043 (-1650 4250);
PAINT GREEN (-1650 4250);
DISPLAY INVISIBLE (-1650 4250);
FORCEPROP 1 LAST HDL_TAP TRUE
J 2
(-1975 4175);
DISPLAY 1.234043 (-1975 4175);
PAINT GREEN (-1975 4175);
DISPLAY INVISIBLE (-1975 4175);
FORCEPROP 1 LAST PATH I56
J 2
(-1650 4300);
DISPLAY 0.936170 (-1650 4300);
PAINT GREEN (-1650 4300);
DISPLAY INVISIBLE (-1650 4300);
FORCEADD TAP..6
R 2
(-1650 4350);
FORCEPROP 3 LASTPIN (-1700 4350) SIG_NAME M_C_DQ<53>
J 0
(-1690 4360);
DISPLAY 0.659574 (-1690 4360);
PAINT MONO (-1690 4360);
DISPLAY INVISIBLE (-1690 4360);
FORCEPROP 1 LASTPIN (-1700 4350) BN 53
J 2
(-1650 4360);
DISPLAY 0.617021 (-1650 4360);
PAINT PINK (-1650 4360);
FORCEPROP 2 LAST CDS_LIB mstr_standard
J 2
(-1650 4350);
DISPLAY 0.787234 (-1650 4350);
PAINT MONO (-1650 4350);
DISPLAY INVISIBLE (-1650 4350);
FORCEPROP 1 LAST BODY_TYPE PLUMBING
J 2
(-1650 4300);
DISPLAY 1.234043 (-1650 4300);
PAINT GREEN (-1650 4300);
DISPLAY INVISIBLE (-1650 4300);
FORCEPROP 1 LAST HDL_TAP TRUE
J 2
(-1975 4225);
DISPLAY 1.234043 (-1975 4225);
PAINT GREEN (-1975 4225);
DISPLAY INVISIBLE (-1975 4225);
FORCEPROP 1 LAST PATH I57
J 2
(-1650 4350);
DISPLAY 0.936170 (-1650 4350);
PAINT GREEN (-1650 4350);
DISPLAY INVISIBLE (-1650 4350);
FORCEADD TAP..6
R 2
(-1650 4250);
FORCEPROP 3 LASTPIN (-1700 4250) SIG_NAME M_C_DQ<51>
J 0
(-1690 4260);
DISPLAY 0.659574 (-1690 4260);
PAINT MONO (-1690 4260);
DISPLAY INVISIBLE (-1690 4260);
FORCEPROP 1 LASTPIN (-1700 4250) BN 51
J 2
(-1650 4260);
DISPLAY 0.617021 (-1650 4260);
PAINT PINK (-1650 4260);
FORCEPROP 2 LAST CDS_LIB mstr_standard
J 2
(-1650 4250);
DISPLAY 0.787234 (-1650 4250);
PAINT MONO (-1650 4250);
DISPLAY INVISIBLE (-1650 4250);
FORCEPROP 1 LAST BODY_TYPE PLUMBING
J 2
(-1650 4200);
DISPLAY 1.234043 (-1650 4200);
PAINT GREEN (-1650 4200);
DISPLAY INVISIBLE (-1650 4200);
FORCEPROP 1 LAST HDL_TAP TRUE
J 2
(-1975 4125);
DISPLAY 1.234043 (-1975 4125);
PAINT GREEN (-1975 4125);
DISPLAY INVISIBLE (-1975 4125);
FORCEPROP 1 LAST PATH I58
J 2
(-1650 4250);
DISPLAY 0.936170 (-1650 4250);
PAINT GREEN (-1650 4250);
DISPLAY INVISIBLE (-1650 4250);
FORCEADD TAP..6
R 2
(-1650 4200);
FORCEPROP 3 LASTPIN (-1700 4200) SIG_NAME M_C_DQ<50>
J 0
(-1690 4210);
DISPLAY 0.659574 (-1690 4210);
PAINT MONO (-1690 4210);
DISPLAY INVISIBLE (-1690 4210);
FORCEPROP 1 LASTPIN (-1700 4200) BN 50
J 2
(-1650 4210);
DISPLAY 0.617021 (-1650 4210);
PAINT PINK (-1650 4210);
FORCEPROP 2 LAST CDS_LIB mstr_standard
J 2
(-1650 4200);
DISPLAY 0.787234 (-1650 4200);
PAINT MONO (-1650 4200);
DISPLAY INVISIBLE (-1650 4200);
FORCEPROP 1 LAST BODY_TYPE PLUMBING
J 2
(-1650 4150);
DISPLAY 1.234043 (-1650 4150);
PAINT GREEN (-1650 4150);
DISPLAY INVISIBLE (-1650 4150);
FORCEPROP 1 LAST HDL_TAP TRUE
J 2
(-1975 4075);
DISPLAY 1.234043 (-1975 4075);
PAINT GREEN (-1975 4075);
DISPLAY INVISIBLE (-1975 4075);
FORCEPROP 1 LAST PATH I59
J 2
(-1650 4200);
DISPLAY 0.936170 (-1650 4200);
PAINT GREEN (-1650 4200);
DISPLAY INVISIBLE (-1650 4200);
FORCEADD TAP..6
R 2
(900 4900);
FORCEPROP 3 LASTPIN (850 4900) SIG_NAME M_C_DQS_DN<15>
J 0
(860 4910);
DISPLAY 0.659574 (860 4910);
PAINT MONO (860 4910);
DISPLAY INVISIBLE (860 4910);
FORCEPROP 1 LASTPIN (850 4900) BN 15
J 2
(900 4910);
DISPLAY 0.617021 (900 4910);
PAINT PINK (900 4910);
FORCEPROP 2 LAST CDS_LIB mstr_standard
J 0
(900 4900);
DISPLAY 0.787234 (900 4900);
PAINT MONO (900 4900);
DISPLAY INVISIBLE (900 4900);
FORCEPROP 1 LAST BODY_TYPE PLUMBING
J 2
(900 4850);
DISPLAY 1.234043 (900 4850);
PAINT GREEN (900 4850);
DISPLAY INVISIBLE (900 4850);
FORCEPROP 1 LAST HDL_TAP TRUE
J 2
(575 4775);
DISPLAY 1.234043 (575 4775);
PAINT GREEN (575 4775);
DISPLAY INVISIBLE (575 4775);
FORCEPROP 1 LAST PATH I6
J 2
(900 4900);
DISPLAY 0.936170 (900 4900);
PAINT GREEN (900 4900);
DISPLAY INVISIBLE (900 4900);
FORCEADD TAP..6
R 2
(-1650 4150);
FORCEPROP 3 LASTPIN (-1700 4150) SIG_NAME M_C_DQ<49>
J 0
(-1690 4160);
DISPLAY 0.659574 (-1690 4160);
PAINT MONO (-1690 4160);
DISPLAY INVISIBLE (-1690 4160);
FORCEPROP 1 LASTPIN (-1700 4150) BN 49
J 2
(-1650 4160);
DISPLAY 0.617021 (-1650 4160);
PAINT PINK (-1650 4160);
FORCEPROP 2 LAST CDS_LIB mstr_standard
J 2
(-1650 4150);
DISPLAY 0.787234 (-1650 4150);
PAINT MONO (-1650 4150);
DISPLAY INVISIBLE (-1650 4150);
FORCEPROP 1 LAST BODY_TYPE PLUMBING
J 2
(-1650 4100);
DISPLAY 1.234043 (-1650 4100);
PAINT GREEN (-1650 4100);
DISPLAY INVISIBLE (-1650 4100);
FORCEPROP 1 LAST HDL_TAP TRUE
J 2
(-1975 4025);
DISPLAY 1.234043 (-1975 4025);
PAINT GREEN (-1975 4025);
DISPLAY INVISIBLE (-1975 4025);
FORCEPROP 1 LAST PATH I60
J 2
(-1650 4150);
DISPLAY 0.936170 (-1650 4150);
PAINT GREEN (-1650 4150);
DISPLAY INVISIBLE (-1650 4150);
FORCEADD SCONN288_H44441003..2
(0 4300);
FORCEPROP 2 LASTPIN (450 4100) $PN 277
J 0
(460 4110);
DISPLAY 0.617021 (460 4110);
PAINT ORANGE (460 4110);
FORCEPROP 1 LAST LOCATION J6U2
J 0
(-400 5400);
DISPLAY 0.617021 (-400 5400);
PAINT AQUA (-400 5400);
FORCEPROP 1 LAST MATERIAL SCONN
J 0
(-400 5350);
DISPLAY 0.617021 (-400 5350);
PAINT SKYBLUE (-400 5350);
FORCEPROP 2 LASTPIN (450 5150) $PN 51
J 0
(460 5160);
DISPLAY 0.617021 (460 5160);
PAINT ORANGE (460 5160);
FORCEPROP 2 LASTPIN (450 5100) $PN 52
J 0
(460 5110);
DISPLAY 0.617021 (460 5110);
PAINT ORANGE (460 5110);
FORCEPROP 2 LASTPIN (450 5050) $PN 132
J 0
(460 5060);
DISPLAY 0.617021 (460 5060);
PAINT ORANGE (460 5060);
FORCEPROP 2 LASTPIN (450 5000) $PN 133
J 0
(460 5010);
DISPLAY 0.617021 (460 5010);
PAINT ORANGE (460 5010);
FORCEPROP 2 LASTPIN (450 4950) $PN 121
J 0
(460 4960);
DISPLAY 0.617021 (460 4960);
PAINT ORANGE (460 4960);
FORCEPROP 2 LASTPIN (450 4900) $PN 122
J 0
(460 4910);
DISPLAY 0.617021 (460 4910);
PAINT ORANGE (460 4910);
FORCEPROP 2 LASTPIN (450 4850) $PN 110
J 0
(460 4860);
DISPLAY 0.617021 (460 4860);
PAINT ORANGE (460 4860);
FORCEPROP 2 LASTPIN (450 4800) $PN 111
J 0
(460 4810);
DISPLAY 0.617021 (460 4810);
PAINT ORANGE (460 4810);
FORCEPROP 2 LASTPIN (450 4750) $PN 99
J 0
(460 4760);
DISPLAY 0.617021 (460 4760);
PAINT ORANGE (460 4760);
FORCEPROP 2 LASTPIN (450 4700) $PN 100
J 0
(460 4710);
DISPLAY 0.617021 (460 4710);
PAINT ORANGE (460 4710);
FORCEPROP 2 LASTPIN (450 4650) $PN 40
J 0
(460 4660);
DISPLAY 0.617021 (460 4660);
PAINT ORANGE (460 4660);
FORCEPROP 2 LASTPIN (450 4600) $PN 41
J 0
(460 4610);
DISPLAY 0.617021 (460 4610);
PAINT ORANGE (460 4610);
FORCEPROP 2 LASTPIN (450 4550) $PN 29
J 0
(460 4560);
DISPLAY 0.617021 (460 4560);
PAINT ORANGE (460 4560);
FORCEPROP 2 LASTPIN (450 4500) $PN 30
J 0
(460 4510);
DISPLAY 0.617021 (460 4510);
PAINT ORANGE (460 4510);
FORCEPROP 2 LASTPIN (450 4450) $PN 18
J 0
(460 4460);
DISPLAY 0.617021 (460 4460);
PAINT ORANGE (460 4460);
FORCEPROP 2 LASTPIN (450 4400) $PN 19
J 0
(460 4410);
DISPLAY 0.617021 (460 4410);
PAINT ORANGE (460 4410);
FORCEPROP 2 LASTPIN (450 4350) $PN 7
J 0
(460 4360);
DISPLAY 0.617021 (460 4360);
PAINT ORANGE (460 4360);
FORCEPROP 2 LASTPIN (450 4300) $PN 8
J 0
(460 4310);
DISPLAY 0.617021 (460 4310);
PAINT ORANGE (460 4310);
FORCEPROP 2 LASTPIN (450 4250) $PN 197
J 0
(460 4260);
DISPLAY 0.617021 (460 4260);
PAINT ORANGE (460 4260);
FORCEPROP 2 LASTPIN (450 4200) $PN 196
J 0
(460 4210);
DISPLAY 0.617021 (460 4210);
PAINT ORANGE (460 4210);
FORCEPROP 2 LASTPIN (450 4150) $PN 278
J 0
(460 4160);
DISPLAY 0.617021 (460 4160);
PAINT ORANGE (460 4160);
FORCEPROP 2 LASTPIN (450 4050) $PN 267
J 0
(460 4060);
DISPLAY 0.617021 (460 4060);
PAINT ORANGE (460 4060);
FORCEPROP 2 LASTPIN (450 4000) $PN 266
J 0
(460 4010);
DISPLAY 0.617021 (460 4010);
PAINT ORANGE (460 4010);
FORCEPROP 2 LASTPIN (450 3950) $PN 256
J 0
(460 3960);
DISPLAY 0.617021 (460 3960);
PAINT ORANGE (460 3960);
FORCEPROP 2 LASTPIN (450 3900) $PN 255
J 0
(460 3910);
DISPLAY 0.617021 (460 3910);
PAINT ORANGE (460 3910);
FORCEPROP 2 LASTPIN (450 3850) $PN 245
J 0
(460 3860);
DISPLAY 0.617021 (460 3860);
PAINT ORANGE (460 3860);
FORCEPROP 2 LASTPIN (450 3800) $PN 244
J 0
(460 3810);
DISPLAY 0.617021 (460 3810);
PAINT ORANGE (460 3810);
FORCEPROP 2 LASTPIN (450 3750) $PN 186
J 0
(460 3760);
DISPLAY 0.617021 (460 3760);
PAINT ORANGE (460 3760);
FORCEPROP 2 LASTPIN (450 3700) $PN 185
J 0
(460 3710);
DISPLAY 0.617021 (460 3710);
PAINT ORANGE (460 3710);
FORCEPROP 2 LASTPIN (450 3650) $PN 175
J 0
(460 3660);
DISPLAY 0.617021 (460 3660);
PAINT ORANGE (460 3660);
FORCEPROP 2 LASTPIN (450 3600) $PN 174
J 0
(460 3610);
DISPLAY 0.617021 (460 3610);
PAINT ORANGE (460 3610);
FORCEPROP 2 LASTPIN (450 3550) $PN 164
J 0
(460 3560);
DISPLAY 0.617021 (460 3560);
PAINT ORANGE (460 3560);
FORCEPROP 2 LASTPIN (450 3500) $PN 163
J 0
(460 3510);
DISPLAY 0.617021 (460 3510);
PAINT ORANGE (460 3510);
FORCEPROP 2 LASTPIN (450 3450) $PN 153
J 0
(460 3460);
DISPLAY 0.617021 (460 3460);
PAINT ORANGE (460 3460);
FORCEPROP 2 LASTPIN (450 3400) $PN 152
J 0
(460 3410);
DISPLAY 0.617021 (460 3410);
PAINT ORANGE (460 3410);
FORCEPROP 1 LAST PART_NUMBER H44441-003
J 0
(-400 3200);
DISPLAY 0.617021 (-400 3200);
PAINT BLUE (-400 3200);
FORCEPROP 0 LAST BOM_SS NOPOP
J 0
(-132 5393);
DISPLAY 1.021277 (-132 5393);
PAINT BROWN (-132 5393);
DISPLAY BOTH (-132 5393);
FORCEPROP 1 LAST PACK_TYPE PIP
J 0
(-400 5450);
PAINT SKYBLUE (-400 5450);
DISPLAY INVISIBLE (-400 5450);
FORCEPROP 2 LAST BOM_COST MEM
J 0
(0 4300);
PAINT ORANGE (0 4300);
DISPLAY INVISIBLE (0 4300);
FORCEPROP 2 LAST CDS_LIB mstr_sconn
J 0
(0 4300);
PAINT ORANGE (0 4300);
DISPLAY INVISIBLE (0 4300);
FORCEPROP 2 LAST SEC_TYPE PIP
J 0
(-400 5450);
DISPLAY 1.021277 (-400 5450);
PAINT ORANGE (-400 5450);
DISPLAY INVISIBLE (-400 5450);
FORCEPROP 2 LAST SEC 2
J 0
(-400 5450);
DISPLAY 0.680851 (-400 5450);
PAINT MONO (-400 5450);
DISPLAY INVISIBLE (-400 5450);
FORCEPROP 2 LAST CDS_LOCATION J6U2
J 0
(-400 5400);
DISPLAY 0.617021 (-400 5400);
PAINT AQUA (-400 5400);
DISPLAY INVISIBLE (-400 5400);
FORCEPROP 1 LAST PATH I61
J 0
(0 5350);
PAINT GREEN (0 5350);
DISPLAY INVISIBLE (0 5350);
FORCEPROP 2 LAST ROOM DDR4_CH_C1
J 0
(-400 5500);
PAINT ORANGE (-400 5500);
DISPLAY INVISIBLE (-400 5500);
FORCEADD TAP..6
R 2
(-1650 4000);
FORCEPROP 3 LASTPIN (-1700 4000) SIG_NAME M_C_DQ<46>
J 0
(-1690 4010);
DISPLAY 0.659574 (-1690 4010);
PAINT MONO (-1690 4010);
DISPLAY INVISIBLE (-1690 4010);
FORCEPROP 1 LASTPIN (-1700 4000) BN 46
J 2
(-1650 4010);
DISPLAY 0.617021 (-1650 4010);
PAINT PINK (-1650 4010);
FORCEPROP 2 LAST CDS_LIB mstr_standard
J 2
(-1650 4000);
DISPLAY 0.787234 (-1650 4000);
PAINT MONO (-1650 4000);
DISPLAY INVISIBLE (-1650 4000);
FORCEPROP 1 LAST BODY_TYPE PLUMBING
J 2
(-1650 3950);
DISPLAY 1.234043 (-1650 3950);
PAINT GREEN (-1650 3950);
DISPLAY INVISIBLE (-1650 3950);
FORCEPROP 1 LAST HDL_TAP TRUE
J 2
(-1975 3875);
DISPLAY 1.234043 (-1975 3875);
PAINT GREEN (-1975 3875);
DISPLAY INVISIBLE (-1975 3875);
FORCEPROP 1 LAST PATH I62
J 2
(-1650 4000);
DISPLAY 0.936170 (-1650 4000);
PAINT GREEN (-1650 4000);
DISPLAY INVISIBLE (-1650 4000);
FORCEADD TAP..6
R 2
(-1650 4050);
FORCEPROP 3 LASTPIN (-1700 4050) SIG_NAME M_C_DQ<47>
J 0
(-1690 4060);
DISPLAY 0.659574 (-1690 4060);
PAINT MONO (-1690 4060);
DISPLAY INVISIBLE (-1690 4060);
FORCEPROP 1 LASTPIN (-1700 4050) BN 47
J 2
(-1650 4060);
DISPLAY 0.617021 (-1650 4060);
PAINT PINK (-1650 4060);
FORCEPROP 2 LAST CDS_LIB mstr_standard
J 2
(-1650 4050);
DISPLAY 0.787234 (-1650 4050);
PAINT MONO (-1650 4050);
DISPLAY INVISIBLE (-1650 4050);
FORCEPROP 1 LAST BODY_TYPE PLUMBING
J 2
(-1650 4000);
DISPLAY 1.234043 (-1650 4000);
PAINT GREEN (-1650 4000);
DISPLAY INVISIBLE (-1650 4000);
FORCEPROP 1 LAST HDL_TAP TRUE
J 2
(-1975 3925);
DISPLAY 1.234043 (-1975 3925);
PAINT GREEN (-1975 3925);
DISPLAY INVISIBLE (-1975 3925);
FORCEPROP 1 LAST PATH I63
J 2
(-1650 4050);
DISPLAY 0.936170 (-1650 4050);
PAINT GREEN (-1650 4050);
DISPLAY INVISIBLE (-1650 4050);
FORCEADD TAP..6
R 2
(-1650 4100);
FORCEPROP 3 LASTPIN (-1700 4100) SIG_NAME M_C_DQ<48>
J 0
(-1690 4110);
DISPLAY 0.659574 (-1690 4110);
PAINT MONO (-1690 4110);
DISPLAY INVISIBLE (-1690 4110);
FORCEPROP 1 LASTPIN (-1700 4100) BN 48
J 2
(-1650 4110);
DISPLAY 0.617021 (-1650 4110);
PAINT PINK (-1650 4110);
FORCEPROP 2 LAST CDS_LIB mstr_standard
J 2
(-1650 4100);
DISPLAY 0.787234 (-1650 4100);
PAINT MONO (-1650 4100);
DISPLAY INVISIBLE (-1650 4100);
FORCEPROP 1 LAST BODY_TYPE PLUMBING
J 2
(-1650 4050);
DISPLAY 1.234043 (-1650 4050);
PAINT GREEN (-1650 4050);
DISPLAY INVISIBLE (-1650 4050);
FORCEPROP 1 LAST HDL_TAP TRUE
J 2
(-1975 3975);
DISPLAY 1.234043 (-1975 3975);
PAINT GREEN (-1975 3975);
DISPLAY INVISIBLE (-1975 3975);
FORCEPROP 1 LAST PATH I64
J 2
(-1650 4100);
DISPLAY 0.936170 (-1650 4100);
PAINT GREEN (-1650 4100);
DISPLAY INVISIBLE (-1650 4100);
FORCEADD TAP..6
R 2
(-1650 3950);
FORCEPROP 3 LASTPIN (-1700 3950) SIG_NAME M_C_DQ<45>
J 0
(-1690 3960);
DISPLAY 0.659574 (-1690 3960);
PAINT MONO (-1690 3960);
DISPLAY INVISIBLE (-1690 3960);
FORCEPROP 1 LASTPIN (-1700 3950) BN 45
J 2
(-1650 3960);
DISPLAY 0.617021 (-1650 3960);
PAINT PINK (-1650 3960);
FORCEPROP 2 LAST CDS_LIB mstr_standard
J 2
(-1650 3950);
DISPLAY 0.787234 (-1650 3950);
PAINT MONO (-1650 3950);
DISPLAY INVISIBLE (-1650 3950);
FORCEPROP 1 LAST BODY_TYPE PLUMBING
J 2
(-1650 3900);
DISPLAY 1.234043 (-1650 3900);
PAINT GREEN (-1650 3900);
DISPLAY INVISIBLE (-1650 3900);
FORCEPROP 1 LAST HDL_TAP TRUE
J 2
(-1975 3825);
DISPLAY 1.234043 (-1975 3825);
PAINT GREEN (-1975 3825);
DISPLAY INVISIBLE (-1975 3825);
FORCEPROP 1 LAST PATH I65
J 2
(-1650 3950);
DISPLAY 0.936170 (-1650 3950);
PAINT GREEN (-1650 3950);
DISPLAY INVISIBLE (-1650 3950);
FORCEADD TAP..6
R 2
(-1650 3900);
FORCEPROP 3 LASTPIN (-1700 3900) SIG_NAME M_C_DQ<44>
J 0
(-1690 3910);
DISPLAY 0.659574 (-1690 3910);
PAINT MONO (-1690 3910);
DISPLAY INVISIBLE (-1690 3910);
FORCEPROP 1 LASTPIN (-1700 3900) BN 44
J 2
(-1650 3910);
DISPLAY 0.617021 (-1650 3910);
PAINT PINK (-1650 3910);
FORCEPROP 2 LAST CDS_LIB mstr_standard
J 2
(-1650 3900);
DISPLAY 0.787234 (-1650 3900);
PAINT MONO (-1650 3900);
DISPLAY INVISIBLE (-1650 3900);
FORCEPROP 1 LAST BODY_TYPE PLUMBING
J 2
(-1650 3850);
DISPLAY 1.234043 (-1650 3850);
PAINT GREEN (-1650 3850);
DISPLAY INVISIBLE (-1650 3850);
FORCEPROP 1 LAST HDL_TAP TRUE
J 2
(-1975 3775);
DISPLAY 1.234043 (-1975 3775);
PAINT GREEN (-1975 3775);
DISPLAY INVISIBLE (-1975 3775);
FORCEPROP 1 LAST PATH I66
J 2
(-1650 3900);
DISPLAY 0.936170 (-1650 3900);
PAINT GREEN (-1650 3900);
DISPLAY INVISIBLE (-1650 3900);
FORCEADD TAP..6
R 2
(-1650 3850);
FORCEPROP 3 LASTPIN (-1700 3850) SIG_NAME M_C_DQ<43>
J 0
(-1690 3860);
DISPLAY 0.659574 (-1690 3860);
PAINT MONO (-1690 3860);
DISPLAY INVISIBLE (-1690 3860);
FORCEPROP 1 LASTPIN (-1700 3850) BN 43
J 2
(-1650 3860);
DISPLAY 0.617021 (-1650 3860);
PAINT PINK (-1650 3860);
FORCEPROP 2 LAST CDS_LIB mstr_standard
J 2
(-1650 3850);
DISPLAY 0.787234 (-1650 3850);
PAINT MONO (-1650 3850);
DISPLAY INVISIBLE (-1650 3850);
FORCEPROP 1 LAST BODY_TYPE PLUMBING
J 2
(-1650 3800);
DISPLAY 1.234043 (-1650 3800);
PAINT GREEN (-1650 3800);
DISPLAY INVISIBLE (-1650 3800);
FORCEPROP 1 LAST HDL_TAP TRUE
J 2
(-1975 3725);
DISPLAY 1.234043 (-1975 3725);
PAINT GREEN (-1975 3725);
DISPLAY INVISIBLE (-1975 3725);
FORCEPROP 1 LAST PATH I67
J 2
(-1650 3850);
DISPLAY 0.936170 (-1650 3850);
PAINT GREEN (-1650 3850);
DISPLAY INVISIBLE (-1650 3850);
FORCEADD TAP..6
R 2
(-1650 3800);
FORCEPROP 3 LASTPIN (-1700 3800) SIG_NAME M_C_DQ<42>
J 0
(-1690 3810);
DISPLAY 0.659574 (-1690 3810);
PAINT MONO (-1690 3810);
DISPLAY INVISIBLE (-1690 3810);
FORCEPROP 1 LASTPIN (-1700 3800) BN 42
J 2
(-1650 3810);
DISPLAY 0.617021 (-1650 3810);
PAINT PINK (-1650 3810);
FORCEPROP 2 LAST CDS_LIB mstr_standard
J 2
(-1650 3800);
DISPLAY 0.787234 (-1650 3800);
PAINT MONO (-1650 3800);
DISPLAY INVISIBLE (-1650 3800);
FORCEPROP 1 LAST BODY_TYPE PLUMBING
J 2
(-1650 3750);
DISPLAY 1.234043 (-1650 3750);
PAINT GREEN (-1650 3750);
DISPLAY INVISIBLE (-1650 3750);
FORCEPROP 1 LAST HDL_TAP TRUE
J 2
(-1975 3675);
DISPLAY 1.234043 (-1975 3675);
PAINT GREEN (-1975 3675);
DISPLAY INVISIBLE (-1975 3675);
FORCEPROP 1 LAST PATH I68
J 2
(-1650 3800);
DISPLAY 0.936170 (-1650 3800);
PAINT GREEN (-1650 3800);
DISPLAY INVISIBLE (-1650 3800);
FORCEADD TAP..6
R 2
(-1650 3750);
FORCEPROP 3 LASTPIN (-1700 3750) SIG_NAME M_C_DQ<41>
J 0
(-1690 3760);
DISPLAY 0.659574 (-1690 3760);
PAINT MONO (-1690 3760);
DISPLAY INVISIBLE (-1690 3760);
FORCEPROP 1 LASTPIN (-1700 3750) BN 41
J 2
(-1650 3760);
DISPLAY 0.617021 (-1650 3760);
PAINT PINK (-1650 3760);
FORCEPROP 2 LAST CDS_LIB mstr_standard
J 2
(-1650 3750);
DISPLAY 0.787234 (-1650 3750);
PAINT MONO (-1650 3750);
DISPLAY INVISIBLE (-1650 3750);
FORCEPROP 1 LAST BODY_TYPE PLUMBING
J 2
(-1650 3700);
DISPLAY 1.234043 (-1650 3700);
PAINT GREEN (-1650 3700);
DISPLAY INVISIBLE (-1650 3700);
FORCEPROP 1 LAST HDL_TAP TRUE
J 2
(-1975 3625);
DISPLAY 1.234043 (-1975 3625);
PAINT GREEN (-1975 3625);
DISPLAY INVISIBLE (-1975 3625);
FORCEPROP 1 LAST PATH I69
J 2
(-1650 3750);
DISPLAY 0.936170 (-1650 3750);
PAINT GREEN (-1650 3750);
DISPLAY INVISIBLE (-1650 3750);
FORCEADD TAP..6
R 2
(900 5000);
FORCEPROP 3 LASTPIN (850 5000) SIG_NAME M_C_DQS_DN<16>
J 0
(860 5010);
DISPLAY 0.659574 (860 5010);
PAINT MONO (860 5010);
DISPLAY INVISIBLE (860 5010);
FORCEPROP 1 LASTPIN (850 5000) BN 16
J 2
(900 5010);
DISPLAY 0.617021 (900 5010);
PAINT PINK (900 5010);
FORCEPROP 2 LAST CDS_LIB mstr_standard
J 0
(900 5000);
DISPLAY 0.787234 (900 5000);
PAINT MONO (900 5000);
DISPLAY INVISIBLE (900 5000);
FORCEPROP 1 LAST BODY_TYPE PLUMBING
J 2
(900 4950);
DISPLAY 1.234043 (900 4950);
PAINT GREEN (900 4950);
DISPLAY INVISIBLE (900 4950);
FORCEPROP 1 LAST HDL_TAP TRUE
J 2
(575 4875);
DISPLAY 1.234043 (575 4875);
PAINT GREEN (575 4875);
DISPLAY INVISIBLE (575 4875);
FORCEPROP 1 LAST PATH I7
J 2
(900 5000);
DISPLAY 0.936170 (900 5000);
PAINT GREEN (900 5000);
DISPLAY INVISIBLE (900 5000);
FORCEADD TAP..6
R 2
(-1650 3650);
FORCEPROP 3 LASTPIN (-1700 3650) SIG_NAME M_C_DQ<39>
J 0
(-1690 3660);
DISPLAY 0.659574 (-1690 3660);
PAINT MONO (-1690 3660);
DISPLAY INVISIBLE (-1690 3660);
FORCEPROP 1 LASTPIN (-1700 3650) BN 39
J 2
(-1650 3660);
DISPLAY 0.617021 (-1650 3660);
PAINT PINK (-1650 3660);
FORCEPROP 2 LAST CDS_LIB mstr_standard
J 2
(-1650 3650);
DISPLAY 0.787234 (-1650 3650);
PAINT MONO (-1650 3650);
DISPLAY INVISIBLE (-1650 3650);
FORCEPROP 1 LAST BODY_TYPE PLUMBING
J 2
(-1650 3600);
DISPLAY 1.234043 (-1650 3600);
PAINT GREEN (-1650 3600);
DISPLAY INVISIBLE (-1650 3600);
FORCEPROP 1 LAST HDL_TAP TRUE
J 2
(-1975 3525);
DISPLAY 1.234043 (-1975 3525);
PAINT GREEN (-1975 3525);
DISPLAY INVISIBLE (-1975 3525);
FORCEPROP 1 LAST PATH I70
J 2
(-1650 3650);
DISPLAY 0.936170 (-1650 3650);
PAINT GREEN (-1650 3650);
DISPLAY INVISIBLE (-1650 3650);
FORCEADD TAP..6
R 2
(-1650 3700);
FORCEPROP 3 LASTPIN (-1700 3700) SIG_NAME M_C_DQ<40>
J 0
(-1690 3710);
DISPLAY 0.659574 (-1690 3710);
PAINT MONO (-1690 3710);
DISPLAY INVISIBLE (-1690 3710);
FORCEPROP 1 LASTPIN (-1700 3700) BN 40
J 2
(-1650 3710);
DISPLAY 0.617021 (-1650 3710);
PAINT PINK (-1650 3710);
FORCEPROP 2 LAST CDS_LIB mstr_standard
J 2
(-1650 3700);
DISPLAY 0.787234 (-1650 3700);
PAINT MONO (-1650 3700);
DISPLAY INVISIBLE (-1650 3700);
FORCEPROP 1 LAST BODY_TYPE PLUMBING
J 2
(-1650 3650);
DISPLAY 1.234043 (-1650 3650);
PAINT GREEN (-1650 3650);
DISPLAY INVISIBLE (-1650 3650);
FORCEPROP 1 LAST HDL_TAP TRUE
J 2
(-1975 3575);
DISPLAY 1.234043 (-1975 3575);
PAINT GREEN (-1975 3575);
DISPLAY INVISIBLE (-1975 3575);
FORCEPROP 1 LAST PATH I71
J 2
(-1650 3700);
DISPLAY 0.936170 (-1650 3700);
PAINT GREEN (-1650 3700);
DISPLAY INVISIBLE (-1650 3700);
FORCEADD TAP..6
R 2
(-1650 3500);
FORCEPROP 3 LASTPIN (-1700 3500) SIG_NAME M_C_DQ<36>
J 0
(-1690 3510);
DISPLAY 0.659574 (-1690 3510);
PAINT MONO (-1690 3510);
DISPLAY INVISIBLE (-1690 3510);
FORCEPROP 1 LASTPIN (-1700 3500) BN 36
J 2
(-1650 3510);
DISPLAY 0.617021 (-1650 3510);
PAINT PINK (-1650 3510);
FORCEPROP 2 LAST CDS_LIB mstr_standard
J 2
(-1650 3500);
DISPLAY 0.787234 (-1650 3500);
PAINT MONO (-1650 3500);
DISPLAY INVISIBLE (-1650 3500);
FORCEPROP 1 LAST BODY_TYPE PLUMBING
J 2
(-1650 3450);
DISPLAY 1.234043 (-1650 3450);
PAINT GREEN (-1650 3450);
DISPLAY INVISIBLE (-1650 3450);
FORCEPROP 1 LAST HDL_TAP TRUE
J 2
(-1975 3375);
DISPLAY 1.234043 (-1975 3375);
PAINT GREEN (-1975 3375);
DISPLAY INVISIBLE (-1975 3375);
FORCEPROP 1 LAST PATH I72
J 2
(-1650 3500);
DISPLAY 0.936170 (-1650 3500);
PAINT GREEN (-1650 3500);
DISPLAY INVISIBLE (-1650 3500);
FORCEADD TAP..6
R 2
(-1650 3550);
FORCEPROP 3 LASTPIN (-1700 3550) SIG_NAME M_C_DQ<37>
J 0
(-1690 3560);
DISPLAY 0.659574 (-1690 3560);
PAINT MONO (-1690 3560);
DISPLAY INVISIBLE (-1690 3560);
FORCEPROP 1 LASTPIN (-1700 3550) BN 37
J 2
(-1650 3560);
DISPLAY 0.617021 (-1650 3560);
PAINT PINK (-1650 3560);
FORCEPROP 2 LAST CDS_LIB mstr_standard
J 2
(-1650 3550);
DISPLAY 0.787234 (-1650 3550);
PAINT MONO (-1650 3550);
DISPLAY INVISIBLE (-1650 3550);
FORCEPROP 1 LAST BODY_TYPE PLUMBING
J 2
(-1650 3500);
DISPLAY 1.234043 (-1650 3500);
PAINT GREEN (-1650 3500);
DISPLAY INVISIBLE (-1650 3500);
FORCEPROP 1 LAST HDL_TAP TRUE
J 2
(-1975 3425);
DISPLAY 1.234043 (-1975 3425);
PAINT GREEN (-1975 3425);
DISPLAY INVISIBLE (-1975 3425);
FORCEPROP 1 LAST PATH I73
J 2
(-1650 3550);
DISPLAY 0.936170 (-1650 3550);
PAINT GREEN (-1650 3550);
DISPLAY INVISIBLE (-1650 3550);
FORCEADD TAP..6
R 2
(-1650 3600);
FORCEPROP 3 LASTPIN (-1700 3600) SIG_NAME M_C_DQ<38>
J 0
(-1690 3610);
DISPLAY 0.659574 (-1690 3610);
PAINT MONO (-1690 3610);
DISPLAY INVISIBLE (-1690 3610);
FORCEPROP 1 LASTPIN (-1700 3600) BN 38
J 2
(-1650 3610);
DISPLAY 0.617021 (-1650 3610);
PAINT PINK (-1650 3610);
FORCEPROP 2 LAST CDS_LIB mstr_standard
J 2
(-1650 3600);
DISPLAY 0.787234 (-1650 3600);
PAINT MONO (-1650 3600);
DISPLAY INVISIBLE (-1650 3600);
FORCEPROP 1 LAST BODY_TYPE PLUMBING
J 2
(-1650 3550);
DISPLAY 1.234043 (-1650 3550);
PAINT GREEN (-1650 3550);
DISPLAY INVISIBLE (-1650 3550);
FORCEPROP 1 LAST HDL_TAP TRUE
J 2
(-1975 3475);
DISPLAY 1.234043 (-1975 3475);
PAINT GREEN (-1975 3475);
DISPLAY INVISIBLE (-1975 3475);
FORCEPROP 1 LAST PATH I74
J 2
(-1650 3600);
DISPLAY 0.936170 (-1650 3600);
PAINT GREEN (-1650 3600);
DISPLAY INVISIBLE (-1650 3600);
FORCEADD TAP..6
R 2
(-1650 3400);
FORCEPROP 3 LASTPIN (-1700 3400) SIG_NAME M_C_DQ<34>
J 0
(-1690 3410);
DISPLAY 0.659574 (-1690 3410);
PAINT MONO (-1690 3410);
DISPLAY INVISIBLE (-1690 3410);
FORCEPROP 1 LASTPIN (-1700 3400) BN 34
J 2
(-1650 3410);
DISPLAY 0.617021 (-1650 3410);
PAINT PINK (-1650 3410);
FORCEPROP 2 LAST CDS_LIB mstr_standard
J 2
(-1650 3400);
DISPLAY 0.787234 (-1650 3400);
PAINT MONO (-1650 3400);
DISPLAY INVISIBLE (-1650 3400);
FORCEPROP 1 LAST BODY_TYPE PLUMBING
J 2
(-1650 3350);
DISPLAY 1.234043 (-1650 3350);
PAINT GREEN (-1650 3350);
DISPLAY INVISIBLE (-1650 3350);
FORCEPROP 1 LAST HDL_TAP TRUE
J 2
(-1975 3275);
DISPLAY 1.234043 (-1975 3275);
PAINT GREEN (-1975 3275);
DISPLAY INVISIBLE (-1975 3275);
FORCEPROP 1 LAST PATH I75
J 2
(-1650 3400);
DISPLAY 0.936170 (-1650 3400);
PAINT GREEN (-1650 3400);
DISPLAY INVISIBLE (-1650 3400);
FORCEADD TAP..6
R 2
(-1650 3450);
FORCEPROP 3 LASTPIN (-1700 3450) SIG_NAME M_C_DQ<35>
J 0
(-1690 3460);
DISPLAY 0.659574 (-1690 3460);
PAINT MONO (-1690 3460);
DISPLAY INVISIBLE (-1690 3460);
FORCEPROP 1 LASTPIN (-1700 3450) BN 35
J 2
(-1650 3460);
DISPLAY 0.617021 (-1650 3460);
PAINT PINK (-1650 3460);
FORCEPROP 2 LAST CDS_LIB mstr_standard
J 2
(-1650 3450);
DISPLAY 0.787234 (-1650 3450);
PAINT MONO (-1650 3450);
DISPLAY INVISIBLE (-1650 3450);
FORCEPROP 1 LAST BODY_TYPE PLUMBING
J 2
(-1650 3400);
DISPLAY 1.234043 (-1650 3400);
PAINT GREEN (-1650 3400);
DISPLAY INVISIBLE (-1650 3400);
FORCEPROP 1 LAST HDL_TAP TRUE
J 2
(-1975 3325);
DISPLAY 1.234043 (-1975 3325);
PAINT GREEN (-1975 3325);
DISPLAY INVISIBLE (-1975 3325);
FORCEPROP 1 LAST PATH I76
J 2
(-1650 3450);
DISPLAY 0.936170 (-1650 3450);
PAINT GREEN (-1650 3450);
DISPLAY INVISIBLE (-1650 3450);
FORCEADD TAP..6
R 2
(-1650 3350);
FORCEPROP 3 LASTPIN (-1700 3350) SIG_NAME M_C_DQ<33>
J 0
(-1690 3360);
DISPLAY 0.659574 (-1690 3360);
PAINT MONO (-1690 3360);
DISPLAY INVISIBLE (-1690 3360);
FORCEPROP 1 LASTPIN (-1700 3350) BN 33
J 2
(-1650 3360);
DISPLAY 0.617021 (-1650 3360);
PAINT PINK (-1650 3360);
FORCEPROP 2 LAST CDS_LIB mstr_standard
J 2
(-1650 3350);
DISPLAY 0.787234 (-1650 3350);
PAINT MONO (-1650 3350);
DISPLAY INVISIBLE (-1650 3350);
FORCEPROP 1 LAST BODY_TYPE PLUMBING
J 2
(-1650 3300);
DISPLAY 1.234043 (-1650 3300);
PAINT GREEN (-1650 3300);
DISPLAY INVISIBLE (-1650 3300);
FORCEPROP 1 LAST HDL_TAP TRUE
J 2
(-1975 3225);
DISPLAY 1.234043 (-1975 3225);
PAINT GREEN (-1975 3225);
DISPLAY INVISIBLE (-1975 3225);
FORCEPROP 1 LAST PATH I77
J 2
(-1650 3350);
DISPLAY 0.936170 (-1650 3350);
PAINT GREEN (-1650 3350);
DISPLAY INVISIBLE (-1650 3350);
FORCEADD TAP..6
R 2
(-1650 3300);
FORCEPROP 3 LASTPIN (-1700 3300) SIG_NAME M_C_DQ<32>
J 0
(-1690 3310);
DISPLAY 0.659574 (-1690 3310);
PAINT MONO (-1690 3310);
DISPLAY INVISIBLE (-1690 3310);
FORCEPROP 1 LASTPIN (-1700 3300) BN 32
J 2
(-1650 3310);
DISPLAY 0.617021 (-1650 3310);
PAINT PINK (-1650 3310);
FORCEPROP 2 LAST CDS_LIB mstr_standard
J 2
(-1650 3300);
DISPLAY 0.787234 (-1650 3300);
PAINT MONO (-1650 3300);
DISPLAY INVISIBLE (-1650 3300);
FORCEPROP 1 LAST BODY_TYPE PLUMBING
J 2
(-1650 3250);
DISPLAY 1.234043 (-1650 3250);
PAINT GREEN (-1650 3250);
DISPLAY INVISIBLE (-1650 3250);
FORCEPROP 1 LAST HDL_TAP TRUE
J 2
(-1975 3175);
DISPLAY 1.234043 (-1975 3175);
PAINT GREEN (-1975 3175);
DISPLAY INVISIBLE (-1975 3175);
FORCEPROP 1 LAST PATH I78
J 2
(-1650 3300);
DISPLAY 0.936170 (-1650 3300);
PAINT GREEN (-1650 3300);
DISPLAY INVISIBLE (-1650 3300);
FORCEADD TAP..6
R 2
(-1650 3250);
FORCEPROP 3 LASTPIN (-1700 3250) SIG_NAME M_C_DQ<31>
J 0
(-1690 3260);
DISPLAY 0.659574 (-1690 3260);
PAINT MONO (-1690 3260);
DISPLAY INVISIBLE (-1690 3260);
FORCEPROP 1 LASTPIN (-1700 3250) BN 31
J 2
(-1650 3260);
DISPLAY 0.617021 (-1650 3260);
PAINT PINK (-1650 3260);
FORCEPROP 2 LAST CDS_LIB mstr_standard
J 2
(-1650 3250);
DISPLAY 0.787234 (-1650 3250);
PAINT MONO (-1650 3250);
DISPLAY INVISIBLE (-1650 3250);
FORCEPROP 1 LAST BODY_TYPE PLUMBING
J 2
(-1650 3200);
DISPLAY 1.234043 (-1650 3200);
PAINT GREEN (-1650 3200);
DISPLAY INVISIBLE (-1650 3200);
FORCEPROP 1 LAST HDL_TAP TRUE
J 2
(-1975 3125);
DISPLAY 1.234043 (-1975 3125);
PAINT GREEN (-1975 3125);
DISPLAY INVISIBLE (-1975 3125);
FORCEPROP 1 LAST PATH I79
J 2
(-1650 3250);
DISPLAY 0.936170 (-1650 3250);
PAINT GREEN (-1650 3250);
DISPLAY INVISIBLE (-1650 3250);
FORCEADD TAP..6
R 2
(900 4800);
FORCEPROP 3 LASTPIN (850 4800) SIG_NAME M_C_DQS_DN<14>
J 0
(860 4810);
DISPLAY 0.659574 (860 4810);
PAINT MONO (860 4810);
DISPLAY INVISIBLE (860 4810);
FORCEPROP 1 LASTPIN (850 4800) BN 14
J 2
(900 4810);
DISPLAY 0.617021 (900 4810);
PAINT PINK (900 4810);
FORCEPROP 2 LAST CDS_LIB mstr_standard
J 0
(900 4800);
DISPLAY 0.787234 (900 4800);
PAINT MONO (900 4800);
DISPLAY INVISIBLE (900 4800);
FORCEPROP 1 LAST BODY_TYPE PLUMBING
J 2
(900 4750);
DISPLAY 1.234043 (900 4750);
PAINT GREEN (900 4750);
DISPLAY INVISIBLE (900 4750);
FORCEPROP 1 LAST HDL_TAP TRUE
J 2
(575 4675);
DISPLAY 1.234043 (575 4675);
PAINT GREEN (575 4675);
DISPLAY INVISIBLE (575 4675);
FORCEPROP 1 LAST PATH I8
J 2
(900 4800);
DISPLAY 0.936170 (900 4800);
PAINT GREEN (900 4800);
DISPLAY INVISIBLE (900 4800);
FORCEADD TAP..6
R 2
(-1650 3100);
FORCEPROP 3 LASTPIN (-1700 3100) SIG_NAME M_C_DQ<28>
J 0
(-1690 3110);
DISPLAY 0.659574 (-1690 3110);
PAINT MONO (-1690 3110);
DISPLAY INVISIBLE (-1690 3110);
FORCEPROP 1 LASTPIN (-1700 3100) BN 28
J 2
(-1650 3110);
DISPLAY 0.617021 (-1650 3110);
PAINT PINK (-1650 3110);
FORCEPROP 2 LAST CDS_LIB mstr_standard
J 2
(-1650 3100);
DISPLAY 0.787234 (-1650 3100);
PAINT MONO (-1650 3100);
DISPLAY INVISIBLE (-1650 3100);
FORCEPROP 1 LAST BODY_TYPE PLUMBING
J 2
(-1650 3050);
DISPLAY 1.234043 (-1650 3050);
PAINT GREEN (-1650 3050);
DISPLAY INVISIBLE (-1650 3050);
FORCEPROP 1 LAST HDL_TAP TRUE
J 2
(-1975 2975);
DISPLAY 1.234043 (-1975 2975);
PAINT GREEN (-1975 2975);
DISPLAY INVISIBLE (-1975 2975);
FORCEPROP 1 LAST PATH I80
J 2
(-1650 3100);
DISPLAY 0.936170 (-1650 3100);
PAINT GREEN (-1650 3100);
DISPLAY INVISIBLE (-1650 3100);
FORCEADD TAP..6
R 2
(-1650 3150);
FORCEPROP 3 LASTPIN (-1700 3150) SIG_NAME M_C_DQ<29>
J 0
(-1690 3160);
DISPLAY 0.659574 (-1690 3160);
PAINT MONO (-1690 3160);
DISPLAY INVISIBLE (-1690 3160);
FORCEPROP 1 LASTPIN (-1700 3150) BN 29
J 2
(-1650 3160);
DISPLAY 0.617021 (-1650 3160);
PAINT PINK (-1650 3160);
FORCEPROP 2 LAST CDS_LIB mstr_standard
J 2
(-1650 3150);
DISPLAY 0.787234 (-1650 3150);
PAINT MONO (-1650 3150);
DISPLAY INVISIBLE (-1650 3150);
FORCEPROP 1 LAST BODY_TYPE PLUMBING
J 2
(-1650 3100);
DISPLAY 1.234043 (-1650 3100);
PAINT GREEN (-1650 3100);
DISPLAY INVISIBLE (-1650 3100);
FORCEPROP 1 LAST HDL_TAP TRUE
J 2
(-1975 3025);
DISPLAY 1.234043 (-1975 3025);
PAINT GREEN (-1975 3025);
DISPLAY INVISIBLE (-1975 3025);
FORCEPROP 1 LAST PATH I81
J 2
(-1650 3150);
DISPLAY 0.936170 (-1650 3150);
PAINT GREEN (-1650 3150);
DISPLAY INVISIBLE (-1650 3150);
FORCEADD TAP..6
R 2
(-1650 3200);
FORCEPROP 3 LASTPIN (-1700 3200) SIG_NAME M_C_DQ<30>
J 0
(-1690 3210);
DISPLAY 0.659574 (-1690 3210);
PAINT MONO (-1690 3210);
DISPLAY INVISIBLE (-1690 3210);
FORCEPROP 1 LASTPIN (-1700 3200) BN 30
J 2
(-1650 3210);
DISPLAY 0.617021 (-1650 3210);
PAINT PINK (-1650 3210);
FORCEPROP 2 LAST CDS_LIB mstr_standard
J 2
(-1650 3200);
DISPLAY 0.787234 (-1650 3200);
PAINT MONO (-1650 3200);
DISPLAY INVISIBLE (-1650 3200);
FORCEPROP 1 LAST BODY_TYPE PLUMBING
J 2
(-1650 3150);
DISPLAY 1.234043 (-1650 3150);
PAINT GREEN (-1650 3150);
DISPLAY INVISIBLE (-1650 3150);
FORCEPROP 1 LAST HDL_TAP TRUE
J 2
(-1975 3075);
DISPLAY 1.234043 (-1975 3075);
PAINT GREEN (-1975 3075);
DISPLAY INVISIBLE (-1975 3075);
FORCEPROP 1 LAST PATH I82
J 2
(-1650 3200);
DISPLAY 0.936170 (-1650 3200);
PAINT GREEN (-1650 3200);
DISPLAY INVISIBLE (-1650 3200);
FORCEADD TAP..6
R 2
(-1650 3050);
FORCEPROP 3 LASTPIN (-1700 3050) SIG_NAME M_C_DQ<27>
J 0
(-1690 3060);
DISPLAY 0.659574 (-1690 3060);
PAINT MONO (-1690 3060);
DISPLAY INVISIBLE (-1690 3060);
FORCEPROP 1 LASTPIN (-1700 3050) BN 27
J 2
(-1650 3060);
DISPLAY 0.617021 (-1650 3060);
PAINT PINK (-1650 3060);
FORCEPROP 2 LAST CDS_LIB mstr_standard
J 2
(-1650 3050);
DISPLAY 0.787234 (-1650 3050);
PAINT MONO (-1650 3050);
DISPLAY INVISIBLE (-1650 3050);
FORCEPROP 1 LAST BODY_TYPE PLUMBING
J 2
(-1650 3000);
DISPLAY 1.234043 (-1650 3000);
PAINT GREEN (-1650 3000);
DISPLAY INVISIBLE (-1650 3000);
FORCEPROP 1 LAST HDL_TAP TRUE
J 2
(-1975 2925);
DISPLAY 1.234043 (-1975 2925);
PAINT GREEN (-1975 2925);
DISPLAY INVISIBLE (-1975 2925);
FORCEPROP 1 LAST PATH I83
J 2
(-1650 3050);
DISPLAY 0.936170 (-1650 3050);
PAINT GREEN (-1650 3050);
DISPLAY INVISIBLE (-1650 3050);
FORCEADD TAP..6
R 2
(-1650 3000);
FORCEPROP 3 LASTPIN (-1700 3000) SIG_NAME M_C_DQ<26>
J 0
(-1690 3010);
DISPLAY 0.659574 (-1690 3010);
PAINT MONO (-1690 3010);
DISPLAY INVISIBLE (-1690 3010);
FORCEPROP 1 LASTPIN (-1700 3000) BN 26
J 2
(-1650 3010);
DISPLAY 0.617021 (-1650 3010);
PAINT PINK (-1650 3010);
FORCEPROP 2 LAST CDS_LIB mstr_standard
J 2
(-1650 3000);
DISPLAY 0.787234 (-1650 3000);
PAINT MONO (-1650 3000);
DISPLAY INVISIBLE (-1650 3000);
FORCEPROP 1 LAST BODY_TYPE PLUMBING
J 2
(-1650 2950);
DISPLAY 1.234043 (-1650 2950);
PAINT GREEN (-1650 2950);
DISPLAY INVISIBLE (-1650 2950);
FORCEPROP 1 LAST HDL_TAP TRUE
J 2
(-1975 2875);
DISPLAY 1.234043 (-1975 2875);
PAINT GREEN (-1975 2875);
DISPLAY INVISIBLE (-1975 2875);
FORCEPROP 1 LAST PATH I84
J 2
(-1650 3000);
DISPLAY 0.936170 (-1650 3000);
PAINT GREEN (-1650 3000);
DISPLAY INVISIBLE (-1650 3000);
FORCEADD TAP..6
R 2
(-1650 2850);
FORCEPROP 3 LASTPIN (-1700 2850) SIG_NAME M_C_DQ<23>
J 0
(-1690 2860);
DISPLAY 0.659574 (-1690 2860);
PAINT MONO (-1690 2860);
DISPLAY INVISIBLE (-1690 2860);
FORCEPROP 1 LASTPIN (-1700 2850) BN 23
J 2
(-1650 2860);
DISPLAY 0.617021 (-1650 2860);
PAINT PINK (-1650 2860);
FORCEPROP 2 LAST CDS_LIB mstr_standard
J 2
(-1650 2850);
DISPLAY 0.787234 (-1650 2850);
PAINT MONO (-1650 2850);
DISPLAY INVISIBLE (-1650 2850);
FORCEPROP 1 LAST BODY_TYPE PLUMBING
J 2
(-1650 2800);
DISPLAY 1.234043 (-1650 2800);
PAINT GREEN (-1650 2800);
DISPLAY INVISIBLE (-1650 2800);
FORCEPROP 1 LAST HDL_TAP TRUE
J 2
(-1975 2725);
DISPLAY 1.234043 (-1975 2725);
PAINT GREEN (-1975 2725);
DISPLAY INVISIBLE (-1975 2725);
FORCEPROP 1 LAST PATH I85
J 2
(-1650 2850);
DISPLAY 0.936170 (-1650 2850);
PAINT GREEN (-1650 2850);
DISPLAY INVISIBLE (-1650 2850);
FORCEADD TAP..6
R 2
(-1650 2950);
FORCEPROP 3 LASTPIN (-1700 2950) SIG_NAME M_C_DQ<25>
J 0
(-1690 2960);
DISPLAY 0.659574 (-1690 2960);
PAINT MONO (-1690 2960);
DISPLAY INVISIBLE (-1690 2960);
FORCEPROP 1 LASTPIN (-1700 2950) BN 25
J 2
(-1650 2960);
DISPLAY 0.617021 (-1650 2960);
PAINT PINK (-1650 2960);
FORCEPROP 2 LAST CDS_LIB mstr_standard
J 2
(-1650 2950);
DISPLAY 0.787234 (-1650 2950);
PAINT MONO (-1650 2950);
DISPLAY INVISIBLE (-1650 2950);
FORCEPROP 1 LAST BODY_TYPE PLUMBING
J 2
(-1650 2900);
DISPLAY 1.234043 (-1650 2900);
PAINT GREEN (-1650 2900);
DISPLAY INVISIBLE (-1650 2900);
FORCEPROP 1 LAST HDL_TAP TRUE
J 2
(-1975 2825);
DISPLAY 1.234043 (-1975 2825);
PAINT GREEN (-1975 2825);
DISPLAY INVISIBLE (-1975 2825);
FORCEPROP 1 LAST PATH I86
J 2
(-1650 2950);
DISPLAY 0.936170 (-1650 2950);
PAINT GREEN (-1650 2950);
DISPLAY INVISIBLE (-1650 2950);
FORCEADD TAP..6
R 2
(-1650 2900);
FORCEPROP 3 LASTPIN (-1700 2900) SIG_NAME M_C_DQ<24>
J 0
(-1690 2910);
DISPLAY 0.659574 (-1690 2910);
PAINT MONO (-1690 2910);
DISPLAY INVISIBLE (-1690 2910);
FORCEPROP 1 LASTPIN (-1700 2900) BN 24
J 2
(-1650 2910);
DISPLAY 0.617021 (-1650 2910);
PAINT PINK (-1650 2910);
FORCEPROP 2 LAST CDS_LIB mstr_standard
J 2
(-1650 2900);
DISPLAY 0.787234 (-1650 2900);
PAINT MONO (-1650 2900);
DISPLAY INVISIBLE (-1650 2900);
FORCEPROP 1 LAST BODY_TYPE PLUMBING
J 2
(-1650 2850);
DISPLAY 1.234043 (-1650 2850);
PAINT GREEN (-1650 2850);
DISPLAY INVISIBLE (-1650 2850);
FORCEPROP 1 LAST HDL_TAP TRUE
J 2
(-1975 2775);
DISPLAY 1.234043 (-1975 2775);
PAINT GREEN (-1975 2775);
DISPLAY INVISIBLE (-1975 2775);
FORCEPROP 1 LAST PATH I87
J 2
(-1650 2900);
DISPLAY 0.936170 (-1650 2900);
PAINT GREEN (-1650 2900);
DISPLAY INVISIBLE (-1650 2900);
FORCEADD TAP..6
R 2
(-1650 2750);
FORCEPROP 3 LASTPIN (-1700 2750) SIG_NAME M_C_DQ<21>
J 0
(-1690 2760);
DISPLAY 0.659574 (-1690 2760);
PAINT MONO (-1690 2760);
DISPLAY INVISIBLE (-1690 2760);
FORCEPROP 1 LASTPIN (-1700 2750) BN 21
J 2
(-1650 2760);
DISPLAY 0.617021 (-1650 2760);
PAINT PINK (-1650 2760);
FORCEPROP 2 LAST CDS_LIB mstr_standard
J 2
(-1650 2750);
DISPLAY 0.787234 (-1650 2750);
PAINT MONO (-1650 2750);
DISPLAY INVISIBLE (-1650 2750);
FORCEPROP 1 LAST BODY_TYPE PLUMBING
J 2
(-1650 2700);
DISPLAY 1.234043 (-1650 2700);
PAINT GREEN (-1650 2700);
DISPLAY INVISIBLE (-1650 2700);
FORCEPROP 1 LAST HDL_TAP TRUE
J 2
(-1975 2625);
DISPLAY 1.234043 (-1975 2625);
PAINT GREEN (-1975 2625);
DISPLAY INVISIBLE (-1975 2625);
FORCEPROP 1 LAST PATH I88
J 2
(-1650 2750);
DISPLAY 0.936170 (-1650 2750);
PAINT GREEN (-1650 2750);
DISPLAY INVISIBLE (-1650 2750);
FORCEADD TAP..6
R 2
(-1650 2800);
FORCEPROP 3 LASTPIN (-1700 2800) SIG_NAME M_C_DQ<22>
J 0
(-1690 2810);
DISPLAY 0.659574 (-1690 2810);
PAINT MONO (-1690 2810);
DISPLAY INVISIBLE (-1690 2810);
FORCEPROP 1 LASTPIN (-1700 2800) BN 22
J 2
(-1650 2810);
DISPLAY 0.617021 (-1650 2810);
PAINT PINK (-1650 2810);
FORCEPROP 2 LAST CDS_LIB mstr_standard
J 2
(-1650 2800);
DISPLAY 0.787234 (-1650 2800);
PAINT MONO (-1650 2800);
DISPLAY INVISIBLE (-1650 2800);
FORCEPROP 1 LAST BODY_TYPE PLUMBING
J 2
(-1650 2750);
DISPLAY 1.234043 (-1650 2750);
PAINT GREEN (-1650 2750);
DISPLAY INVISIBLE (-1650 2750);
FORCEPROP 1 LAST HDL_TAP TRUE
J 2
(-1975 2675);
DISPLAY 1.234043 (-1975 2675);
PAINT GREEN (-1975 2675);
DISPLAY INVISIBLE (-1975 2675);
FORCEPROP 1 LAST PATH I89
J 2
(-1650 2800);
DISPLAY 0.936170 (-1650 2800);
PAINT GREEN (-1650 2800);
DISPLAY INVISIBLE (-1650 2800);
FORCEADD TAP..6
R 2
(700 4950);
FORCEPROP 3 LASTPIN (650 4950) SIG_NAME M_C_DQS_DP<15>
J 0
(660 4960);
DISPLAY 0.659574 (660 4960);
PAINT MONO (660 4960);
DISPLAY INVISIBLE (660 4960);
FORCEPROP 1 LASTPIN (650 4950) BN 15
J 2
(700 4960);
DISPLAY 0.617021 (700 4960);
PAINT PINK (700 4960);
FORCEPROP 2 LAST CDS_LIB mstr_standard
J 0
(700 4950);
DISPLAY 0.787234 (700 4950);
PAINT MONO (700 4950);
DISPLAY INVISIBLE (700 4950);
FORCEPROP 1 LAST BODY_TYPE PLUMBING
J 2
(700 4900);
DISPLAY 1.234043 (700 4900);
PAINT GREEN (700 4900);
DISPLAY INVISIBLE (700 4900);
FORCEPROP 1 LAST HDL_TAP TRUE
J 2
(375 4825);
DISPLAY 1.234043 (375 4825);
PAINT WHITE (375 4825);
DISPLAY INVISIBLE (375 4825);
FORCEPROP 1 LAST PATH I9
J 2
(700 4950);
DISPLAY 0.936170 (700 4950);
PAINT GREEN (700 4950);
DISPLAY INVISIBLE (700 4950);
FORCEADD TAP..6
R 2
(-1650 2700);
FORCEPROP 3 LASTPIN (-1700 2700) SIG_NAME M_C_DQ<20>
J 0
(-1690 2710);
DISPLAY 0.659574 (-1690 2710);
PAINT MONO (-1690 2710);
DISPLAY INVISIBLE (-1690 2710);
FORCEPROP 1 LASTPIN (-1700 2700) BN 20
J 2
(-1650 2710);
DISPLAY 0.617021 (-1650 2710);
PAINT PINK (-1650 2710);
FORCEPROP 2 LAST CDS_LIB mstr_standard
J 2
(-1650 2700);
DISPLAY 0.787234 (-1650 2700);
PAINT MONO (-1650 2700);
DISPLAY INVISIBLE (-1650 2700);
FORCEPROP 1 LAST BODY_TYPE PLUMBING
J 2
(-1650 2650);
DISPLAY 1.234043 (-1650 2650);
PAINT GREEN (-1650 2650);
DISPLAY INVISIBLE (-1650 2650);
FORCEPROP 1 LAST HDL_TAP TRUE
J 2
(-1975 2575);
DISPLAY 1.234043 (-1975 2575);
PAINT GREEN (-1975 2575);
DISPLAY INVISIBLE (-1975 2575);
FORCEPROP 1 LAST PATH I90
J 2
(-1650 2700);
DISPLAY 0.936170 (-1650 2700);
PAINT GREEN (-1650 2700);
DISPLAY INVISIBLE (-1650 2700);
FORCEADD TAP..6
R 2
(-1650 2650);
FORCEPROP 3 LASTPIN (-1700 2650) SIG_NAME M_C_DQ<19>
J 0
(-1690 2660);
DISPLAY 0.659574 (-1690 2660);
PAINT MONO (-1690 2660);
DISPLAY INVISIBLE (-1690 2660);
FORCEPROP 1 LASTPIN (-1700 2650) BN 19
J 2
(-1650 2660);
DISPLAY 0.617021 (-1650 2660);
PAINT PINK (-1650 2660);
FORCEPROP 2 LAST CDS_LIB mstr_standard
J 2
(-1650 2650);
DISPLAY 0.787234 (-1650 2650);
PAINT MONO (-1650 2650);
DISPLAY INVISIBLE (-1650 2650);
FORCEPROP 1 LAST BODY_TYPE PLUMBING
J 2
(-1650 2600);
DISPLAY 1.234043 (-1650 2600);
PAINT GREEN (-1650 2600);
DISPLAY INVISIBLE (-1650 2600);
FORCEPROP 1 LAST HDL_TAP TRUE
J 2
(-1975 2525);
DISPLAY 1.234043 (-1975 2525);
PAINT GREEN (-1975 2525);
DISPLAY INVISIBLE (-1975 2525);
FORCEPROP 1 LAST PATH I91
J 2
(-1650 2650);
DISPLAY 0.936170 (-1650 2650);
PAINT GREEN (-1650 2650);
DISPLAY INVISIBLE (-1650 2650);
FORCEADD TAP..6
R 2
(-1650 2600);
FORCEPROP 3 LASTPIN (-1700 2600) SIG_NAME M_C_DQ<18>
J 0
(-1690 2610);
DISPLAY 0.659574 (-1690 2610);
PAINT MONO (-1690 2610);
DISPLAY INVISIBLE (-1690 2610);
FORCEPROP 1 LASTPIN (-1700 2600) BN 18
J 2
(-1650 2610);
DISPLAY 0.617021 (-1650 2610);
PAINT PINK (-1650 2610);
FORCEPROP 2 LAST CDS_LIB mstr_standard
J 2
(-1650 2600);
DISPLAY 0.787234 (-1650 2600);
PAINT MONO (-1650 2600);
DISPLAY INVISIBLE (-1650 2600);
FORCEPROP 1 LAST BODY_TYPE PLUMBING
J 2
(-1650 2550);
DISPLAY 1.234043 (-1650 2550);
PAINT GREEN (-1650 2550);
DISPLAY INVISIBLE (-1650 2550);
FORCEPROP 1 LAST HDL_TAP TRUE
J 2
(-1975 2475);
DISPLAY 1.234043 (-1975 2475);
PAINT GREEN (-1975 2475);
DISPLAY INVISIBLE (-1975 2475);
FORCEPROP 1 LAST PATH I92
J 2
(-1650 2600);
DISPLAY 0.936170 (-1650 2600);
PAINT GREEN (-1650 2600);
DISPLAY INVISIBLE (-1650 2600);
FORCEADD TAP..6
R 2
(-1650 2500);
FORCEPROP 3 LASTPIN (-1700 2500) SIG_NAME M_C_DQ<16>
J 0
(-1690 2510);
DISPLAY 0.659574 (-1690 2510);
PAINT MONO (-1690 2510);
DISPLAY INVISIBLE (-1690 2510);
FORCEPROP 1 LASTPIN (-1700 2500) BN 16
J 2
(-1650 2510);
DISPLAY 0.617021 (-1650 2510);
PAINT PINK (-1650 2510);
FORCEPROP 2 LAST CDS_LIB mstr_standard
J 2
(-1650 2500);
DISPLAY 0.787234 (-1650 2500);
PAINT MONO (-1650 2500);
DISPLAY INVISIBLE (-1650 2500);
FORCEPROP 1 LAST BODY_TYPE PLUMBING
J 2
(-1650 2450);
DISPLAY 1.234043 (-1650 2450);
PAINT GREEN (-1650 2450);
DISPLAY INVISIBLE (-1650 2450);
FORCEPROP 1 LAST HDL_TAP TRUE
J 2
(-1975 2375);
DISPLAY 1.234043 (-1975 2375);
PAINT GREEN (-1975 2375);
DISPLAY INVISIBLE (-1975 2375);
FORCEPROP 1 LAST PATH I93
J 2
(-1650 2500);
DISPLAY 0.936170 (-1650 2500);
PAINT GREEN (-1650 2500);
DISPLAY INVISIBLE (-1650 2500);
FORCEADD TAP..6
R 2
(-1650 2550);
FORCEPROP 3 LASTPIN (-1700 2550) SIG_NAME M_C_DQ<17>
J 0
(-1690 2560);
DISPLAY 0.659574 (-1690 2560);
PAINT MONO (-1690 2560);
DISPLAY INVISIBLE (-1690 2560);
FORCEPROP 1 LASTPIN (-1700 2550) BN 17
J 2
(-1650 2560);
DISPLAY 0.617021 (-1650 2560);
PAINT PINK (-1650 2560);
FORCEPROP 2 LAST CDS_LIB mstr_standard
J 2
(-1650 2550);
DISPLAY 0.787234 (-1650 2550);
PAINT MONO (-1650 2550);
DISPLAY INVISIBLE (-1650 2550);
FORCEPROP 1 LAST BODY_TYPE PLUMBING
J 2
(-1650 2500);
DISPLAY 1.234043 (-1650 2500);
PAINT GREEN (-1650 2500);
DISPLAY INVISIBLE (-1650 2500);
FORCEPROP 1 LAST HDL_TAP TRUE
J 2
(-1975 2425);
DISPLAY 1.234043 (-1975 2425);
PAINT GREEN (-1975 2425);
DISPLAY INVISIBLE (-1975 2425);
FORCEPROP 1 LAST PATH I94
J 2
(-1650 2550);
DISPLAY 0.936170 (-1650 2550);
PAINT GREEN (-1650 2550);
DISPLAY INVISIBLE (-1650 2550);
FORCEADD TAP..6
R 2
(-1650 2350);
FORCEPROP 3 LASTPIN (-1700 2350) SIG_NAME M_C_DQ<13>
J 0
(-1690 2360);
DISPLAY 0.659574 (-1690 2360);
PAINT MONO (-1690 2360);
DISPLAY INVISIBLE (-1690 2360);
FORCEPROP 1 LASTPIN (-1700 2350) BN 13
J 2
(-1650 2360);
DISPLAY 0.617021 (-1650 2360);
PAINT PINK (-1650 2360);
FORCEPROP 2 LAST CDS_LIB mstr_standard
J 2
(-1650 2350);
DISPLAY 0.787234 (-1650 2350);
PAINT MONO (-1650 2350);
DISPLAY INVISIBLE (-1650 2350);
FORCEPROP 1 LAST BODY_TYPE PLUMBING
J 2
(-1650 2300);
DISPLAY 1.234043 (-1650 2300);
PAINT GREEN (-1650 2300);
DISPLAY INVISIBLE (-1650 2300);
FORCEPROP 1 LAST HDL_TAP TRUE
J 2
(-1975 2225);
DISPLAY 1.234043 (-1975 2225);
PAINT GREEN (-1975 2225);
DISPLAY INVISIBLE (-1975 2225);
FORCEPROP 1 LAST PATH I95
J 2
(-1650 2350);
DISPLAY 0.936170 (-1650 2350);
PAINT GREEN (-1650 2350);
DISPLAY INVISIBLE (-1650 2350);
FORCEADD TAP..6
R 2
(-1650 2400);
FORCEPROP 3 LASTPIN (-1700 2400) SIG_NAME M_C_DQ<14>
J 0
(-1690 2410);
DISPLAY 0.659574 (-1690 2410);
PAINT MONO (-1690 2410);
DISPLAY INVISIBLE (-1690 2410);
FORCEPROP 1 LASTPIN (-1700 2400) BN 14
J 2
(-1650 2410);
DISPLAY 0.617021 (-1650 2410);
PAINT PINK (-1650 2410);
FORCEPROP 2 LAST CDS_LIB mstr_standard
J 2
(-1650 2400);
DISPLAY 0.787234 (-1650 2400);
PAINT MONO (-1650 2400);
DISPLAY INVISIBLE (-1650 2400);
FORCEPROP 1 LAST BODY_TYPE PLUMBING
J 2
(-1650 2350);
DISPLAY 1.234043 (-1650 2350);
PAINT GREEN (-1650 2350);
DISPLAY INVISIBLE (-1650 2350);
FORCEPROP 1 LAST HDL_TAP TRUE
J 2
(-1975 2275);
DISPLAY 1.234043 (-1975 2275);
PAINT GREEN (-1975 2275);
DISPLAY INVISIBLE (-1975 2275);
FORCEPROP 1 LAST PATH I96
J 2
(-1650 2400);
DISPLAY 0.936170 (-1650 2400);
PAINT GREEN (-1650 2400);
DISPLAY INVISIBLE (-1650 2400);
FORCEADD TAP..6
R 2
(-1650 2450);
FORCEPROP 3 LASTPIN (-1700 2450) SIG_NAME M_C_DQ<15>
J 0
(-1690 2460);
DISPLAY 0.659574 (-1690 2460);
PAINT MONO (-1690 2460);
DISPLAY INVISIBLE (-1690 2460);
FORCEPROP 1 LASTPIN (-1700 2450) BN 15
J 2
(-1650 2460);
DISPLAY 0.617021 (-1650 2460);
PAINT PINK (-1650 2460);
FORCEPROP 2 LAST CDS_LIB mstr_standard
J 2
(-1650 2450);
DISPLAY 0.787234 (-1650 2450);
PAINT MONO (-1650 2450);
DISPLAY INVISIBLE (-1650 2450);
FORCEPROP 1 LAST BODY_TYPE PLUMBING
J 2
(-1650 2400);
DISPLAY 1.234043 (-1650 2400);
PAINT GREEN (-1650 2400);
DISPLAY INVISIBLE (-1650 2400);
FORCEPROP 1 LAST HDL_TAP TRUE
J 2
(-1975 2325);
DISPLAY 1.234043 (-1975 2325);
PAINT GREEN (-1975 2325);
DISPLAY INVISIBLE (-1975 2325);
FORCEPROP 1 LAST PATH I97
J 2
(-1650 2450);
DISPLAY 0.936170 (-1650 2450);
PAINT GREEN (-1650 2450);
DISPLAY INVISIBLE (-1650 2450);
FORCEADD TAP..6
R 2
(-1650 2250);
FORCEPROP 3 LASTPIN (-1700 2250) SIG_NAME M_C_DQ<11>
J 0
(-1690 2260);
DISPLAY 0.659574 (-1690 2260);
PAINT MONO (-1690 2260);
DISPLAY INVISIBLE (-1690 2260);
FORCEPROP 1 LASTPIN (-1700 2250) BN 11
J 2
(-1650 2260);
DISPLAY 0.617021 (-1650 2260);
PAINT PINK (-1650 2260);
FORCEPROP 2 LAST CDS_LIB mstr_standard
J 2
(-1650 2250);
DISPLAY 0.787234 (-1650 2250);
PAINT MONO (-1650 2250);
DISPLAY INVISIBLE (-1650 2250);
FORCEPROP 1 LAST BODY_TYPE PLUMBING
J 2
(-1650 2200);
DISPLAY 1.234043 (-1650 2200);
PAINT GREEN (-1650 2200);
DISPLAY INVISIBLE (-1650 2200);
FORCEPROP 1 LAST HDL_TAP TRUE
J 2
(-1975 2125);
DISPLAY 1.234043 (-1975 2125);
PAINT GREEN (-1975 2125);
DISPLAY INVISIBLE (-1975 2125);
FORCEPROP 1 LAST PATH I98
J 2
(-1650 2250);
DISPLAY 0.936170 (-1650 2250);
PAINT GREEN (-1650 2250);
DISPLAY INVISIBLE (-1650 2250);
FORCEADD TAP..6
R 2
(-1650 2300);
FORCEPROP 3 LASTPIN (-1700 2300) SIG_NAME M_C_DQ<12>
J 0
(-1690 2310);
DISPLAY 0.659574 (-1690 2310);
PAINT MONO (-1690 2310);
DISPLAY INVISIBLE (-1690 2310);
FORCEPROP 1 LASTPIN (-1700 2300) BN 12
J 2
(-1650 2310);
DISPLAY 0.617021 (-1650 2310);
PAINT PINK (-1650 2310);
FORCEPROP 2 LAST CDS_LIB mstr_standard
J 2
(-1650 2300);
DISPLAY 0.787234 (-1650 2300);
PAINT MONO (-1650 2300);
DISPLAY INVISIBLE (-1650 2300);
FORCEPROP 1 LAST BODY_TYPE PLUMBING
J 2
(-1650 2250);
DISPLAY 1.234043 (-1650 2250);
PAINT GREEN (-1650 2250);
DISPLAY INVISIBLE (-1650 2250);
FORCEPROP 1 LAST HDL_TAP TRUE
J 2
(-1975 2175);
DISPLAY 1.234043 (-1975 2175);
PAINT GREEN (-1975 2175);
DISPLAY INVISIBLE (-1975 2175);
FORCEPROP 1 LAST PATH I99
J 2
(-1650 2300);
DISPLAY 0.936170 (-1650 2300);
PAINT GREEN (-1650 2300);
DISPLAY INVISIBLE (-1650 2300);
FORCEADD INTEL_CORP_BPAGE..1
(2650 500);
FORCEPROP 1 LAST CDS_CON_LAST_MODIFIED Fri Jun 16 17:48:18 2017
J 0
(1225 825);
DISPLAY 0.787234 (1225 825);
PAINT ORANGE (1225 825);
DISPLAY INVISIBLE (1225 825);
FORCEPROP 1 LAST CUSTOM_TXT_CDS <CURRENT_DESIGN_SHEET> OF <TOTAL_DESIGN_SHEETS>
J 0
(2150 525);
PAINT ORANGE (2150 525);
FORCEPROP 2 LAST CUSTOM_TXT_CDS <XR_PAGE_TITLE>
J 0
(-5240 5750);
DISPLAY 0.638298 (-5240 5750);
PAINT PINK (-5240 5750);
DISPLAY INVISIBLE (-5240 5750);
FORCEPROP 2 LAST CUSTOM_TXT_CDS <CON_LAST_MODIFIED>
J 0
(-1350 600);
DISPLAY 1.042553 (-1350 600);
PAINT ORANGE (-1350 600);
FORCEPROP 1 LAST SCH_TITLE CPU0 DDR4 CH C DIMM1
J 0
(-5300 550);
DISPLAY 1.212766 (-5300 550);
PAINT WHITE (-5300 550);
FORCEPROP 2 LAST CDS_LIB mstr_symbols
J 0
(2650 500);
DISPLAY 0.787234 (2650 500);
PAINT MONO (2650 500);
DISPLAY INVISIBLE (2650 500);
FORCEPROP 2 LAST PAGE_BORDER TRUE
J 0
(-5240 5750);
DISPLAY 0.680851 (-5240 5750);
PAINT PINK (-5240 5750);
DISPLAY INVISIBLE (-5240 5750);
FORCEPROP 1 LAST COMMENT_BODY TRUE
J 0
(2660 510);
DISPLAY 0.382979 (2660 510);
PAINT GREEN (2660 510);
DISPLAY INVISIBLE (2660 510);
FORCEPROP 2 LAST CDS_XR_PAGE_TITLE CR-48 : @BASEBOARD_FAB2_LIB.BASEBOARD_FAB2(SCH_1):PAGE48
J 0
(-5240 5750);
DISPLAY 0.638298 (-5240 5750);
PAINT PINK (-5240 5750);
DISPLAY INVISIBLE (-5240 5750);
FORCEADD BOM_NOTE..1
(-4950 5200);
FORCEPROP 0 LAST L1 UNSTUFF FOR SKU B
J 0
(-5100 5100);
DISPLAY 1.063830 (-5100 5100);
PAINT WHITE (-5100 5100);
FORCEPROP 2 LAST CDS_LIB mstr_symbols
J 0
(-4950 5200);
PAINT ORANGE (-4950 5200);
DISPLAY INVISIBLE (-4950 5200);
FORCEPROP 2 LAST BOM_COST SB
J 0
(-5100 5175);
DISPLAY 1.361702 (-5100 5175);
PAINT ORANGE (-5100 5175);
DISPLAY INVISIBLE (-5100 5175);
FORCEPROP 1 LAST COMMENT_BODY TRUE
J 0
(-4925 5300);
DISPLAY 1.319149 (-4925 5300);
PAINT ORANGE (-4925 5300);
DISPLAY INVISIBLE (-4925 5300);
FORCEPROP 2 LAST ROOM SB_HEADERS
J 0
(-5100 5175);
DISPLAY 1.361702 (-5100 5175);
PAINT ORANGE (-5100 5175);
DISPLAY INVISIBLE (-5100 5175);
WIRE 16 -1 (-950 2650)(-950 2550);
WIRE 16 -1 (-950 2550)(-800 2550);
WIRE 16 -1 (-800 2500)(-800 2550);
WIRE 16 -1 (-800 2550)(-600 2550);
WIRE 16 -1 (-800 2500)(-600 2500);
WIRE 16 -1 (-1150 2500)(-1150 2400);
WIRE 16 -1 (-1150 2400)(-800 2400);
WIRE 16 -1 (-800 2350)(-800 2400);
WIRE 16 -1 (-800 2400)(-600 2400);
WIRE 16 -1 (-800 2300)(-800 2350);
WIRE 16 -1 (-800 2350)(-600 2350);
WIRE 16 -1 (-800 2250)(-800 2300);
WIRE 16 -1 (-800 2300)(-600 2300);
WIRE 16 -1 (-800 2200)(-800 2250);
WIRE 16 -1 (-800 2250)(-600 2250);
WIRE 16 -1 (-800 2150)(-800 2200);
WIRE 16 -1 (-800 2200)(-600 2200);
WIRE 16 -1 (-800 2100)(-800 2150);
WIRE 16 -1 (-800 2150)(-600 2150);
WIRE 16 -1 (-800 2050)(-800 2100);
WIRE 16 -1 (-800 2100)(-600 2100);
WIRE 16 -1 (-800 2000)(-800 2050);
WIRE 16 -1 (-800 2050)(-600 2050);
WIRE 16 -1 (-800 1950)(-800 2000);
WIRE 16 -1 (-800 2000)(-600 2000);
WIRE 16 -1 (-800 1900)(-800 1950);
WIRE 16 -1 (-800 1950)(-600 1950);
WIRE 16 -1 (-800 1850)(-800 1900);
WIRE 16 -1 (-800 1900)(-600 1900);
WIRE 16 -1 (-800 1800)(-800 1850);
WIRE 16 -1 (-800 1850)(-600 1850);
WIRE 16 -1 (-800 1750)(-800 1800);
WIRE 16 -1 (-800 1800)(-600 1800);
WIRE 16 -1 (-800 1700)(-800 1750);
WIRE 16 -1 (-800 1750)(-600 1750);
WIRE 16 -1 (-800 1650)(-800 1700);
WIRE 16 -1 (-800 1700)(-600 1700);
WIRE 16 -1 (-800 1600)(-800 1650);
WIRE 16 -1 (-800 1650)(-600 1650);
WIRE 16 -1 (-800 1550)(-800 1600);
WIRE 16 -1 (-800 1600)(-600 1600);
WIRE 16 -1 (-800 1500)(-800 1550);
WIRE 16 -1 (-800 1550)(-600 1550);
WIRE 16 -1 (-800 1450)(-800 1500);
WIRE 16 -1 (-800 1500)(-600 1500);
WIRE 16 -1 (-800 1400)(-800 1450);
WIRE 16 -1 (-800 1450)(-600 1450);
WIRE 16 -1 (-800 1350)(-800 1400);
WIRE 16 -1 (-800 1400)(-600 1400);
WIRE 16 -1 (-800 1300)(-800 1350);
WIRE 16 -1 (-800 1350)(-600 1350);
WIRE 16 -1 (-800 1250)(-800 1300);
WIRE 16 -1 (-800 1300)(-600 1300);
WIRE 16 -1 (-800 1200)(-800 1250);
WIRE 16 -1 (-800 1250)(-600 1250);
WIRE 16 -1 (-800 1150)(-800 1200);
WIRE 16 -1 (-800 1200)(-600 1200);
WIRE 16 -1 (-800 1150)(-600 1150);
WIRE 16 -1 (2500 1350)(2500 1450);
WIRE 16 -1 (2500 1450)(2500 1500);
WIRE 16 -1 (2500 1450)(2300 1450);
WIRE 16 -1 (2500 1500)(2500 1550);
WIRE 16 -1 (2500 1500)(2300 1500);
WIRE 16 -1 (2500 1550)(2500 1600);
WIRE 16 -1 (2500 1550)(2300 1550);
WIRE 16 -1 (2500 1600)(2500 1650);
WIRE 16 -1 (2500 1600)(2300 1600);
WIRE 16 -1 (2500 1650)(2500 1700);
WIRE 16 -1 (2500 1650)(2300 1650);
WIRE 16 -1 (2500 1700)(2500 1750);
WIRE 16 -1 (2500 1700)(2300 1700);
WIRE 16 -1 (2500 1750)(2500 1800);
WIRE 16 -1 (2500 1750)(2300 1750);
WIRE 16 -1 (2500 1800)(2500 1850);
WIRE 16 -1 (2500 1800)(2300 1800);
WIRE 16 -1 (2500 1850)(2500 1900);
WIRE 16 -1 (2500 1850)(2300 1850);
WIRE 16 -1 (2500 1900)(2500 1950);
WIRE 16 -1 (2500 1900)(2300 1900);
WIRE 16 -1 (2500 1950)(2500 2000);
WIRE 16 -1 (2500 1950)(2300 1950);
WIRE 16 -1 (2500 2000)(2500 2050);
WIRE 16 -1 (2500 2000)(2300 2000);
WIRE 16 -1 (2500 2050)(2500 2100);
WIRE 16 -1 (2500 2050)(2300 2050);
WIRE 16 -1 (2500 2100)(2500 2150);
WIRE 16 -1 (2500 2100)(2300 2100);
WIRE 16 -1 (2500 2150)(2500 2200);
WIRE 16 -1 (2500 2150)(2300 2150);
WIRE 16 -1 (2500 2200)(2500 2250);
WIRE 16 -1 (2500 2200)(2300 2200);
WIRE 16 -1 (2500 2250)(2500 2300);
WIRE 16 -1 (2500 2250)(2300 2250);
WIRE 16 -1 (2500 2300)(2500 2350);
WIRE 16 -1 (2500 2300)(2300 2300);
WIRE 16 -1 (2500 2350)(2500 2400);
WIRE 16 -1 (2500 2350)(2300 2350);
WIRE 16 -1 (2500 2400)(2500 2450);
WIRE 16 -1 (2500 2400)(2300 2400);
WIRE 16 -1 (2500 2450)(2500 2500);
WIRE 16 -1 (2500 2450)(2300 2450);
WIRE 16 -1 (2500 2500)(2500 2550);
WIRE 16 -1 (2500 2500)(2300 2500);
WIRE 16 -1 (2500 2550)(2500 2600);
WIRE 16 -1 (2500 2550)(2300 2550);
WIRE 16 -1 (2500 2600)(2500 2650);
WIRE 16 -1 (2500 2600)(2300 2600);
WIRE 16 -1 (2500 2650)(2500 2700);
WIRE 16 -1 (2500 2650)(2300 2650);
WIRE 16 -1 (2500 2700)(2500 2750);
WIRE 16 -1 (2500 2700)(2300 2700);
WIRE 16 -1 (2500 2750)(2500 2800);
WIRE 16 -1 (2500 2750)(2300 2750);
WIRE 16 -1 (2500 2800)(2500 2850);
WIRE 16 -1 (2500 2800)(2300 2800);
WIRE 16 -1 (2500 2850)(2500 2900);
WIRE 16 -1 (2500 2850)(2300 2850);
WIRE 16 -1 (2500 2900)(2500 2950);
WIRE 16 -1 (2500 2900)(2300 2900);
WIRE 16 -1 (2500 2950)(2500 3000);
WIRE 16 -1 (2500 2950)(2300 2950);
WIRE 16 -1 (2500 3000)(2500 3050);
WIRE 16 -1 (2500 3000)(2300 3000);
WIRE 16 -1 (2500 3050)(2500 3100);
WIRE 16 -1 (2500 3050)(2300 3050);
WIRE 16 -1 (2500 3100)(2500 3150);
WIRE 16 -1 (2500 3100)(2300 3100);
WIRE 16 -1 (2500 3150)(2500 3200);
WIRE 16 -1 (2500 3150)(2300 3150);
WIRE 16 -1 (2500 3200)(2500 3250);
WIRE 16 -1 (2500 3200)(2300 3200);
WIRE 16 -1 (2500 3250)(2500 3300);
WIRE 16 -1 (2500 3250)(2300 3250);
WIRE 16 -1 (2500 3300)(2500 3350);
WIRE 16 -1 (2500 3300)(2300 3300);
WIRE 16 -1 (2500 3350)(2500 3400);
WIRE 16 -1 (2500 3350)(2300 3350);
WIRE 16 -1 (2500 3400)(2500 3450);
WIRE 16 -1 (2500 3400)(2300 3400);
WIRE 16 -1 (2500 3450)(2500 3500);
WIRE 16 -1 (2500 3450)(2300 3450);
WIRE 16 -1 (2500 3500)(2500 3550);
WIRE 16 -1 (2500 3500)(2300 3500);
WIRE 16 -1 (2500 3550)(2500 3600);
WIRE 16 -1 (2500 3550)(2300 3550);
WIRE 16 -1 (2500 3600)(2500 3650);
WIRE 16 -1 (2500 3600)(2300 3600);
WIRE 16 -1 (2500 3650)(2500 3700);
WIRE 16 -1 (2500 3650)(2300 3650);
WIRE 16 -1 (2500 3700)(2500 3750);
WIRE 16 -1 (2500 3700)(2300 3700);
WIRE 16 -1 (2500 3750)(2300 3750);
WIRE 16 -1 (-4650 1400)(-4650 1300);
WIRE 16 -1 (-800 2950)(-800 2850);
WIRE 16 -1 (-800 2800)(-800 2850);
WIRE 16 -1 (-800 2850)(-600 2850);
WIRE 16 -1 (-800 2800)(-800 2750);
WIRE 16 -1 (-800 2800)(-600 2800);
WIRE 16 -1 (-800 2700)(-800 2750);
WIRE 16 -1 (-600 2750)(-800 2750);
WIRE 16 -1 (-800 2650)(-800 2700);
WIRE 16 -1 (-800 2700)(-600 2700);
WIRE 16 -1 (-800 2650)(-600 2650);
WIRE 16 -1 (-4650 2200)(-4650 2050);
WIRE 16 -1 (-3100 2050)(-4650 2050);
WIRE 16 -1 (-3100 2000)(-3100 2050);
WIRE 16 -1 (-2900 2050)(-3100 2050);
WIRE 16 -1 (-3100 1900)(-3100 2000);
WIRE 16 -1 (-2900 2000)(-3100 2000);
WIRE 16 -1 (-2900 1900)(-3100 1900);
WIRE 16 -1 (-4650 1950)(-4650 1900);
WIRE 16 -1 (-2900 1950)(-4650 1950);
WIRE 16 -1 (600 2850)(600 3025);
WIRE 16 -1 (600 2800)(600 2850);
WIRE 16 -1 (400 2850)(600 2850);
WIRE 16 -1 (400 2800)(600 2800);
WIRE 16 -1 (1100 1350)(1100 1450);
WIRE 16 -1 (1100 1450)(1100 1500);
WIRE 16 -1 (1100 1450)(1300 1450);
WIRE 16 -1 (1100 1500)(1100 1550);
WIRE 16 -1 (1100 1500)(1300 1500);
WIRE 16 -1 (1100 1550)(1100 1600);
WIRE 16 -1 (1100 1550)(1300 1550);
WIRE 16 -1 (1100 1600)(1100 1650);
WIRE 16 -1 (1100 1600)(1300 1600);
WIRE 16 -1 (1100 1650)(1100 1700);
WIRE 16 -1 (1100 1650)(1300 1650);
WIRE 16 -1 (1100 1700)(1100 1750);
WIRE 16 -1 (1100 1700)(1300 1700);
WIRE 16 -1 (1100 1750)(1100 1800);
WIRE 16 -1 (1100 1750)(1300 1750);
WIRE 16 -1 (1100 1800)(1100 1850);
WIRE 16 -1 (1100 1800)(1300 1800);
WIRE 16 -1 (1100 1850)(1100 1900);
WIRE 16 -1 (1100 1850)(1300 1850);
WIRE 16 -1 (1100 1900)(1100 1950);
WIRE 16 -1 (1100 1900)(1300 1900);
WIRE 16 -1 (1100 1950)(1100 2000);
WIRE 16 -1 (1100 1950)(1300 1950);
WIRE 16 -1 (1100 2000)(1100 2050);
WIRE 16 -1 (1100 2000)(1300 2000);
WIRE 16 -1 (1100 2050)(1100 2100);
WIRE 16 -1 (1100 2050)(1300 2050);
WIRE 16 -1 (1100 2100)(1100 2150);
WIRE 16 -1 (1100 2100)(1300 2100);
WIRE 16 -1 (1100 2150)(1100 2200);
WIRE 16 -1 (1100 2150)(1300 2150);
WIRE 16 -1 (1100 2200)(1100 2250);
WIRE 16 -1 (1100 2200)(1300 2200);
WIRE 16 -1 (1100 2250)(1100 2300);
WIRE 16 -1 (1100 2250)(1300 2250);
WIRE 16 -1 (1100 2300)(1100 2350);
WIRE 16 -1 (1100 2300)(1300 2300);
WIRE 16 -1 (1100 2350)(1100 2400);
WIRE 16 -1 (1100 2350)(1300 2350);
WIRE 16 -1 (1100 2400)(1100 2450);
WIRE 16 -1 (1100 2400)(1300 2400);
WIRE 16 -1 (1100 2450)(1100 2500);
WIRE 16 -1 (1100 2450)(1300 2450);
WIRE 16 -1 (1100 2500)(1100 2550);
WIRE 16 -1 (1100 2500)(1300 2500);
WIRE 16 -1 (1100 2550)(1100 2600);
WIRE 16 -1 (1100 2550)(1300 2550);
WIRE 16 -1 (1100 2600)(1100 2650);
WIRE 16 -1 (1100 2600)(1300 2600);
WIRE 16 -1 (1100 2650)(1100 2700);
WIRE 16 -1 (1100 2650)(1300 2650);
WIRE 16 -1 (1100 2700)(1100 2750);
WIRE 16 -1 (1100 2700)(1300 2700);
WIRE 16 -1 (1100 2750)(1100 2800);
WIRE 16 -1 (1100 2750)(1300 2750);
WIRE 16 -1 (1100 2800)(1100 2850);
WIRE 16 -1 (1100 2800)(1300 2800);
WIRE 16 -1 (1100 2850)(1100 2900);
WIRE 16 -1 (1100 2850)(1300 2850);
WIRE 16 -1 (1100 2900)(1100 2950);
WIRE 16 -1 (1100 2900)(1300 2900);
WIRE 16 -1 (1100 2950)(1100 3000);
WIRE 16 -1 (1100 2950)(1300 2950);
WIRE 16 -1 (1100 3000)(1100 3050);
WIRE 16 -1 (1100 3000)(1300 3000);
WIRE 16 -1 (1100 3050)(1100 3100);
WIRE 16 -1 (1100 3050)(1300 3050);
WIRE 16 -1 (1100 3100)(1100 3150);
WIRE 16 -1 (1100 3100)(1300 3100);
WIRE 16 -1 (1100 3150)(1100 3200);
WIRE 16 -1 (1100 3150)(1300 3150);
WIRE 16 -1 (1100 3200)(1100 3250);
WIRE 16 -1 (1100 3200)(1300 3200);
WIRE 16 -1 (1100 3250)(1100 3300);
WIRE 16 -1 (1100 3250)(1300 3250);
WIRE 16 -1 (1100 3300)(1100 3350);
WIRE 16 -1 (1100 3300)(1300 3300);
WIRE 16 -1 (1100 3350)(1100 3400);
WIRE 16 -1 (1100 3350)(1300 3350);
WIRE 16 -1 (1100 3400)(1100 3450);
WIRE 16 -1 (1100 3400)(1300 3400);
WIRE 16 -1 (1100 3450)(1100 3500);
WIRE 16 -1 (1100 3450)(1300 3450);
WIRE 16 -1 (1100 3500)(1100 3550);
WIRE 16 -1 (1100 3500)(1300 3500);
WIRE 16 -1 (1100 3550)(1100 3600);
WIRE 16 -1 (1100 3550)(1300 3550);
WIRE 16 -1 (1100 3600)(1100 3650);
WIRE 16 -1 (1100 3600)(1300 3600);
WIRE 16 -1 (1100 3650)(1100 3700);
WIRE 16 -1 (1100 3650)(1300 3650);
WIRE 16 -1 (1100 3700)(1100 3750);
WIRE 16 -1 (1100 3700)(1300 3700);
WIRE 16 -1 (1100 3750)(1300 3750);
WIRE 17 -1 (-3400 3625)(-3400 3525);
WIRE 17 -1 (-3400 3650)(-3900 3650);
FORCEPROP 2 LAST SIG_NAME M_C_CLK_DN<3:0>
J 0
(-3850 3660);
DISPLAY 0.617021 (-3850 3660);
PAINT ORANGE (-3850 3660);
WIRE 17 -1 (-3400 3650)(-3400 3625);
WIRE 17 -1 (-3200 3700)(-3900 3700);
FORCEPROP 2 LAST SIG_NAME M_C_CLK_DP<3:0>
J 0
(-3850 3710);
DISPLAY 0.617021 (-3850 3710);
PAINT ORANGE (-3850 3710);
WIRE 17 -1 (-3200 3700)(-3200 3675);
WIRE 17 -1 (-3200 3575)(-3200 3675);
WIRE 17 -1 (-3200 3225)(-3200 3275);
WIRE 17 -1 (-3200 3400)(-3700 3400);
FORCEPROP 2 LAST SIG_NAME M_C_CS_N<7:0>
J 0
(-3650 3410);
DISPLAY 0.617021 (-3650 3410);
PAINT ORANGE (-3650 3410);
WIRE 17 -1 (-3200 3400)(-3200 3375);
WIRE 17 -1 (-3200 3275)(-3200 3325);
WIRE 17 -1 (-3200 3325)(-3200 3375);
WIRE 17 -1 (-3700 4900)(-3200 4900);
FORCEPROP 2 LAST SIG_NAME M_C_MA<17:0>
J 0
(-3650 4910);
DISPLAY 0.617021 (-3650 4910);
PAINT ORANGE (-3650 4910);
WIRE 17 -1 (-3200 4875)(-3200 4900);
WIRE 17 -1 (-3200 4825)(-3200 4875);
WIRE 17 -1 (-3200 4775)(-3200 4825);
WIRE 17 -1 (-3200 4725)(-3200 4775);
WIRE 17 -1 (-3200 4675)(-3200 4725);
WIRE 17 -1 (-3200 4625)(-3200 4675);
WIRE 17 -1 (-3200 4575)(-3200 4625);
WIRE 17 -1 (-3200 4525)(-3200 4575);
WIRE 17 -1 (-3200 4475)(-3200 4525);
WIRE 17 -1 (-3200 4425)(-3200 4475);
WIRE 17 -1 (-3200 4375)(-3200 4425);
WIRE 17 -1 (-3200 4325)(-3200 4375);
WIRE 17 -1 (-3200 4275)(-3200 4325);
WIRE 17 -1 (-3200 4225)(-3200 4275);
WIRE 17 -1 (-3200 4175)(-3200 4225);
WIRE 17 -1 (-3200 4125)(-3200 4175);
WIRE 17 -1 (-3200 4025)(-3200 4075);
WIRE 17 -1 (-3200 4075)(-3200 4125);
WIRE 17 -1 (-3200 2475)(-3200 2525);
WIRE 17 -1 (-3200 2525)(-3200 2575);
WIRE 17 -1 (-3200 2575)(-3200 2625);
WIRE 17 -1 (-3200 2625)(-3200 2675);
WIRE 17 -1 (-3200 2675)(-3200 2725);
WIRE 17 -1 (-3200 2850)(-3700 2850);
FORCEPROP 2 LAST SIG_NAME M_C_ECC<7:0>
J 0
(-3650 2860);
DISPLAY 0.617021 (-3650 2860);
PAINT ORANGE (-3650 2860);
WIRE 17 -1 (-3200 2850)(-3200 2825);
WIRE 17 -1 (-3200 2725)(-3200 2775);
WIRE 17 -1 (-3200 2775)(-3200 2825);
WIRE 17 -1 (-3200 3150)(-3700 3150);
FORCEPROP 2 LAST SIG_NAME M_C_CKE<3:0>
J 0
(-3650 3160);
DISPLAY 0.617021 (-3650 3160);
PAINT ORANGE (-3650 3160);
WIRE 17 -1 (-3200 3150)(-3200 3125);
WIRE 17 -1 (-3200 3075)(-3200 3125);
WIRE 17 -1 (-3200 3850)(-3700 3850);
FORCEPROP 2 LAST SIG_NAME M_C_BG<1:0>
J 0
(-3650 3860);
DISPLAY 0.617021 (-3650 3860);
PAINT ORANGE (-3650 3860);
WIRE 17 -1 (-3200 3850)(-3200 3825);
WIRE 17 -1 (-3200 3775)(-3200 3825);
WIRE 17 -1 (-3200 3000)(-3700 3000);
FORCEPROP 2 LAST SIG_NAME M_C_ODT<3:0>
J 0
(-3650 3010);
DISPLAY 0.617021 (-3650 3010);
PAINT ORANGE (-3650 3010);
WIRE 17 -1 (-3200 3000)(-3200 2975);
WIRE 17 -1 (-3200 2925)(-3200 2975);
WIRE 17 -1 (-1150 4900)(-1600 4900);
FORCEPROP 2 LAST SIG_NAME M_C_DQ<63:0>
J 0
(-1560 4910);
DISPLAY 0.617021 (-1560 4910);
PAINT ORANGE (-1560 4910);
WIRE 17 -1 (-1600 4875)(-1600 4900);
WIRE 17 -1 (-1600 4825)(-1600 4875);
WIRE 17 -1 (-1600 4775)(-1600 4825);
WIRE 17 -1 (-1600 4725)(-1600 4775);
WIRE 17 -1 (-1600 4675)(-1600 4725);
WIRE 17 -1 (-1600 4625)(-1600 4675);
WIRE 17 -1 (-1600 4575)(-1600 4625);
WIRE 17 -1 (-1600 4525)(-1600 4575);
WIRE 17 -1 (-1600 4475)(-1600 4525);
WIRE 17 -1 (-1600 4425)(-1600 4475);
WIRE 17 -1 (-1600 4375)(-1600 4425);
WIRE 17 -1 (-1600 4325)(-1600 4375);
WIRE 17 -1 (-1600 4275)(-1600 4325);
WIRE 17 -1 (-1600 4225)(-1600 4275);
WIRE 17 -1 (-1600 4175)(-1600 4225);
WIRE 17 -1 (-1600 4125)(-1600 4175);
WIRE 17 -1 (-1600 4075)(-1600 4125);
WIRE 17 -1 (-1600 4025)(-1600 4075);
WIRE 17 -1 (-1600 3975)(-1600 4025);
WIRE 17 -1 (-1600 3925)(-1600 3975);
WIRE 17 -1 (-1600 3875)(-1600 3925);
WIRE 17 -1 (-1600 3825)(-1600 3875);
WIRE 17 -1 (-1600 3775)(-1600 3825);
WIRE 17 -1 (-1600 3725)(-1600 3775);
WIRE 17 -1 (-1600 3675)(-1600 3725);
WIRE 17 -1 (-1600 3625)(-1600 3675);
WIRE 17 -1 (-1600 3575)(-1600 3625);
WIRE 17 -1 (-1600 3525)(-1600 3575);
WIRE 17 -1 (-1600 3475)(-1600 3525);
WIRE 17 -1 (-1600 3425)(-1600 3475);
WIRE 17 -1 (-1600 3375)(-1600 3425);
WIRE 17 -1 (-1600 3325)(-1600 3375);
WIRE 17 -1 (-1600 3275)(-1600 3325);
WIRE 17 -1 (-1600 3225)(-1600 3275);
WIRE 17 -1 (-1600 3175)(-1600 3225);
WIRE 17 -1 (-1600 3125)(-1600 3175);
WIRE 17 -1 (-1600 3075)(-1600 3125);
WIRE 17 -1 (-1600 3025)(-1600 3075);
WIRE 17 -1 (-1600 2975)(-1600 3025);
WIRE 17 -1 (-1600 2925)(-1600 2975);
WIRE 17 -1 (-1600 2875)(-1600 2925);
WIRE 17 -1 (-1600 2825)(-1600 2875);
WIRE 17 -1 (-1600 2775)(-1600 2825);
WIRE 17 -1 (-1600 2725)(-1600 2775);
WIRE 17 -1 (-1600 2675)(-1600 2725);
WIRE 17 -1 (-1600 2625)(-1600 2675);
WIRE 17 -1 (-1600 2575)(-1600 2625);
WIRE 17 -1 (-1600 2525)(-1600 2575);
WIRE 17 -1 (-1600 2475)(-1600 2525);
WIRE 17 -1 (-1600 2425)(-1600 2475);
WIRE 17 -1 (-1600 2375)(-1600 2425);
WIRE 17 -1 (-1600 1725)(-1600 1775);
WIRE 17 -1 (-1600 2325)(-1600 2375);
WIRE 17 -1 (-1600 2275)(-1600 2325);
WIRE 17 -1 (-1600 1775)(-1600 1825);
WIRE 17 -1 (-1600 1825)(-1600 1875);
WIRE 17 -1 (-1600 2225)(-1600 2275);
WIRE 17 -1 (-1600 2175)(-1600 2225);
WIRE 17 -1 (-1600 1875)(-1600 1925);
WIRE 17 -1 (-1600 1925)(-1600 1975);
WIRE 17 -1 (-1600 2125)(-1600 2175);
WIRE 17 -1 (-1600 2075)(-1600 2125);
WIRE 17 -1 (-1600 1975)(-1600 2025);
WIRE 17 -1 (-1600 2025)(-1600 2075);
WIRE 17 -1 (1550 5150)(950 5150);
FORCEPROP 2 LAST SIG_NAME M_C_DQS_DN<17:0>
J 0
(1000 5160);
DISPLAY 0.617021 (1000 5160);
PAINT ORANGE (1000 5160);
WIRE 17 -1 (950 5125)(950 5150);
WIRE 17 -1 (950 5025)(950 5125);
WIRE 17 -1 (950 4925)(950 5025);
WIRE 17 -1 (950 4825)(950 4925);
WIRE 17 -1 (950 4725)(950 4825);
WIRE 17 -1 (950 4625)(950 4725);
WIRE 17 -1 (950 4525)(950 4625);
WIRE 17 -1 (950 4425)(950 4525);
WIRE 17 -1 (950 4325)(950 4425);
WIRE 17 -1 (950 4225)(950 4325);
WIRE 17 -1 (950 4125)(950 4225);
WIRE 17 -1 (950 4025)(950 4125);
WIRE 17 -1 (950 3925)(950 4025);
WIRE 17 -1 (950 3825)(950 3925);
WIRE 17 -1 (950 3725)(950 3825);
WIRE 17 -1 (950 3625)(950 3725);
WIRE 17 -1 (950 3525)(950 3625);
WIRE 17 -1 (950 3425)(950 3525);
WIRE 17 -1 (1550 5200)(750 5200);
FORCEPROP 2 LAST SIG_NAME M_C_DQS_DP<17:0>
J 0
(1000 5210);
DISPLAY 0.617021 (1000 5210);
PAINT ORANGE (1000 5210);
WIRE 17 -1 (750 5175)(750 5200);
WIRE 17 -1 (750 5075)(750 5175);
WIRE 17 -1 (750 4975)(750 5075);
WIRE 17 -1 (750 4875)(750 4975);
WIRE 17 -1 (750 4775)(750 4875);
WIRE 17 -1 (750 4675)(750 4775);
WIRE 17 -1 (750 4575)(750 4675);
WIRE 17 -1 (750 4475)(750 4575);
WIRE 17 -1 (750 4375)(750 4475);
WIRE 17 -1 (750 4275)(750 4375);
WIRE 17 -1 (750 4175)(750 4275);
WIRE 17 -1 (750 4075)(750 4175);
WIRE 17 -1 (750 3975)(750 4075);
WIRE 17 -1 (750 3875)(750 3975);
WIRE 17 -1 (750 3775)(750 3875);
WIRE 17 -1 (750 3675)(750 3775);
WIRE 17 -1 (750 3575)(750 3675);
WIRE 17 -1 (750 3475)(750 3575);
WIRE 17 -1 (-3200 3950)(-3700 3950);
FORCEPROP 2 LAST SIG_NAME M_C_BA<1:0>
J 0
(-3650 3960);
DISPLAY 0.617021 (-3650 3960);
PAINT ORANGE (-3650 3960);
WIRE 17 -1 (-3200 3950)(-3200 3925);
WIRE 17 -1 (-3200 3875)(-3200 3925);
WIRE 16 -1 (-1700 4700)(-1900 4700);
WIRE 16 -1 (850 5100)(450 5100);
WIRE 16 -1 (850 5000)(450 5000);
WIRE 16 -1 (-1700 3350)(-1900 3350);
WIRE 16 -1 (-2900 4250)(-3100 4250);
WIRE 16 -1 (-2900 4200)(-3100 4200);
WIRE 16 -1 (-2900 4000)(-3100 4000);
WIRE 16 -1 (-2900 3900)(-3100 3900);
WIRE 16 -1 (-2900 3850)(-3100 3850);
WIRE 16 -1 (-2900 3800)(-3100 3800);
WIRE 16 -1 (650 4350)(450 4350);
WIRE 16 -1 (-1700 3950)(-1900 3950);
WIRE 16 -1 (-1700 3900)(-1900 3900);
WIRE 16 -1 (-1700 3850)(-1900 3850);
WIRE 16 -1 (-1700 3800)(-1900 3800);
WIRE 16 -1 (-1700 3750)(-1900 3750);
WIRE 16 -1 (-1700 3700)(-1900 3700);
WIRE 16 -1 (-1700 3600)(-1900 3600);
WIRE 16 -1 (850 4200)(450 4200);
WIRE 16 -1 (650 4150)(450 4150);
WIRE 16 -1 (850 3600)(450 3600);
WIRE 16 -1 (850 3800)(450 3800);
WIRE 16 -1 (650 4050)(450 4050);
WIRE 16 -1 (850 3900)(450 3900);
WIRE 16 -1 (-1700 4850)(-1900 4850);
WIRE 16 -1 (-1700 4800)(-1900 4800);
WIRE 16 -1 (-1700 4450)(-1900 4450);
WIRE 16 -1 (850 4800)(450 4800);
WIRE 16 -1 (650 5150)(450 5150);
WIRE 16 -1 (850 4300)(450 4300);
WIRE 16 -1 (650 4250)(450 4250);
WIRE 16 -1 (850 4100)(450 4100);
WIRE 16 -1 (650 5050)(450 5050);
WIRE 16 -1 (650 4950)(450 4950);
WIRE 16 -1 (850 4900)(450 4900);
WIRE 16 -1 (650 4850)(450 4850);
WIRE 16 -1 (650 4750)(450 4750);
WIRE 16 -1 (850 4700)(450 4700);
WIRE 16 -1 (650 4650)(450 4650);
WIRE 16 -1 (850 4600)(450 4600);
WIRE 16 -1 (650 4550)(450 4550);
WIRE 16 -1 (850 4500)(450 4500);
WIRE 16 -1 (650 4450)(450 4450);
WIRE 16 -1 (850 4400)(450 4400);
WIRE 16 -1 (850 4000)(450 4000);
WIRE 16 -1 (650 3950)(450 3950);
WIRE 16 -1 (650 3850)(450 3850);
WIRE 16 -1 (650 3750)(450 3750);
WIRE 16 -1 (850 3700)(450 3700);
WIRE 16 -1 (650 3650)(450 3650);
WIRE 16 -1 (650 3550)(450 3550);
WIRE 16 -1 (850 3500)(450 3500);
WIRE 16 -1 (650 3450)(450 3450);
WIRE 16 -1 (850 3400)(450 3400);
WIRE 16 -1 (-1700 4650)(-1900 4650);
WIRE 16 -1 (-1700 4750)(-1900 4750);
WIRE 16 -1 (-1700 4100)(-1900 4100);
WIRE 16 -1 (-1700 4150)(-1900 4150);
WIRE 16 -1 (-1700 4200)(-1900 4200);
WIRE 16 -1 (-1700 4250)(-1900 4250);
WIRE 16 -1 (-1700 4300)(-1900 4300);
WIRE 16 -1 (-1700 4350)(-1900 4350);
WIRE 16 -1 (-1700 4400)(-1900 4400);
WIRE 16 -1 (-1700 4600)(-1900 4600);
WIRE 16 -1 (-1700 4550)(-1900 4550);
WIRE 16 -1 (-1700 4500)(-1900 4500);
WIRE 16 -1 (-2900 4800)(-3100 4800);
WIRE 16 -1 (-2900 4750)(-3100 4750);
WIRE 16 -1 (-2900 4700)(-3100 4700);
WIRE 16 -1 (-2900 4550)(-3100 4550);
WIRE 16 -1 (-2900 4500)(-3100 4500);
WIRE 16 -1 (-2900 4100)(-3100 4100);
WIRE 16 -1 (-2900 4450)(-3100 4450);
WIRE 16 -1 (-2900 4400)(-3100 4400);
WIRE 16 -1 (-2900 4350)(-3100 4350);
WIRE 16 -1 (-2900 4300)(-3100 4300);
WIRE 16 -1 (-2900 4150)(-3100 4150);
WIRE 16 -1 (-2900 4850)(-3100 4850);
WIRE 16 -1 (-2900 4650)(-3100 4650);
WIRE 16 -1 (-2900 4600)(-3100 4600);
WIRE 16 -1 (-1700 4050)(-1900 4050);
WIRE 16 -1 (-1700 3650)(-1900 3650);
WIRE 16 -1 (-1700 4000)(-1900 4000);
WIRE 16 -1 (-1700 3500)(-1900 3500);
WIRE 16 -1 (-1700 3450)(-1900 3450);
WIRE 16 -1 (-1700 3200)(-1900 3200);
WIRE 16 -1 (-1700 3250)(-1900 3250);
WIRE 16 -1 (-1700 3300)(-1900 3300);
WIRE 16 -1 (-1700 3400)(-1900 3400);
WIRE 16 -1 (-1700 3550)(-1900 3550);
WIRE 16 -1 (-1700 3100)(-1900 3100);
WIRE 16 -1 (-1700 3150)(-1900 3150);
WIRE 16 -1 (-1700 2700)(-1900 2700);
WIRE 16 -1 (-1700 3000)(-1900 3000);
WIRE 16 -1 (-1700 3050)(-1900 3050);
WIRE 16 -1 (-1700 2600)(-1900 2600);
WIRE 16 -1 (-1700 2650)(-1900 2650);
WIRE 16 -1 (-1700 2750)(-1900 2750);
WIRE 16 -1 (-1700 2800)(-1900 2800);
WIRE 16 -1 (-1700 2850)(-1900 2850);
WIRE 16 -1 (-1700 2900)(-1900 2900);
WIRE 16 -1 (-1700 2950)(-1900 2950);
WIRE 16 -1 (-1700 2250)(-1900 2250);
WIRE 16 -1 (-1700 2550)(-1900 2550);
WIRE 16 -1 (-1700 2450)(-1900 2450);
WIRE 16 -1 (-1700 2050)(-1900 2050);
WIRE 16 -1 (-1700 2100)(-1900 2100);
WIRE 16 -1 (-1700 2150)(-1900 2150);
WIRE 16 -1 (-1700 2200)(-1900 2200);
WIRE 16 -1 (-1700 2300)(-1900 2300);
WIRE 16 -1 (-1700 2350)(-1900 2350);
WIRE 16 -1 (-1700 2400)(-1900 2400);
WIRE 16 -1 (-1700 2500)(-1900 2500);
WIRE 16 -1 (-1700 1950)(-1900 1950);
WIRE 16 -1 (-1700 1900)(-1900 1900);
WIRE 16 -1 (-1700 1850)(-1900 1850);
WIRE 16 -1 (-1700 1800)(-1900 1800);
WIRE 16 -1 (-1700 1700)(-1900 1700);
WIRE 16 -1 (-1700 1750)(-1900 1750);
WIRE 16 -1 (-1700 2000)(-1900 2000);
WIRE 16 -1 (-3050 3450)(-3700 3450);
FORCEPROP 2 LAST SIG_NAME M_C_C<2>
J 0
(-3650 3460);
DISPLAY 0.617021 (-3650 3460);
PAINT ORANGE (-3650 3460);
WIRE 16 -1 (-3050 3400)(-3050 3450);
WIRE 16 -1 (-3050 3400)(-2900 3400);
WIRE 16 -1 (-3900 2150)(-2900 2150);
FORCEPROP 2 LAST SIG_NAME M_C_ACT_N
J 0
(-3875 2160);
DISPLAY 0.617021 (-3875 2160);
PAINT ORANGE (-3875 2160);
WIRE 16 -1 (-3925 2200)(-2900 2200);
FORCEPROP 2 LAST SIG_NAME M_C_ALERT_N
J 0
(-3900 2210);
DISPLAY 0.617021 (-3900 2210);
PAINT ORANGE (-3900 2210);
WIRE 16 -1 (-2900 3500)(-3300 3500);
WIRE 16 -1 (-2900 3350)(-3100 3350);
WIRE 16 -1 (-2900 3050)(-3100 3050);
WIRE 16 -1 (-2900 2950)(-3100 2950);
WIRE 16 -1 (-2900 3200)(-3100 3200);
WIRE 16 -1 (-2900 2900)(-3100 2900);
WIRE 16 -1 (-2900 2800)(-3100 2800);
WIRE 16 -1 (-2900 3750)(-3100 3750);
WIRE 16 -1 (-2900 3650)(-3100 3650);
WIRE 16 -1 (-2900 3100)(-3100 3100);
WIRE 16 -1 (-2900 2450)(-3100 2450);
WIRE 16 -1 (-2900 2500)(-3100 2500);
WIRE 16 -1 (-2900 2550)(-3100 2550);
WIRE 16 -1 (-2900 2600)(-3100 2600);
WIRE 16 -1 (-2900 2650)(-3100 2650);
WIRE 16 -1 (-2900 2700)(-3100 2700);
WIRE 16 -1 (-2900 2750)(-3100 2750);
WIRE 16 -1 (-2900 4050)(-3100 4050);
WIRE 16 -1 (-2900 3250)(-3100 3250);
WIRE 16 -1 (-2900 3300)(-3100 3300);
WIRE 16 -1 (-2900 3550)(-3100 3550);
WIRE 16 -1 (-2900 3600)(-3300 3600);
WIRE 16 -1 (-3300 2750)(-3700 2750);
FORCEPROP 2 LAST SIG_NAME M_ABC_RST_N
J 0
(-3650 2760);
DISPLAY 0.617021 (-3650 2760);
PAINT ORANGE (-3650 2760);
WIRE 16 -1 (-3300 2300)(-3300 2750);
WIRE 16 -1 (-3300 2300)(-2900 2300);
WIRE 16 -1 (-3250 2800)(-3700 2800);
FORCEPROP 2 LAST SIG_NAME M_C_PAR
J 0
(-3650 2810);
DISPLAY 0.617021 (-3650 2810);
PAINT ORANGE (-3650 2810);
WIRE 16 -1 (-3250 2350)(-3250 2800);
WIRE 16 -1 (-3250 2350)(-2900 2350);
WIRE 16 -1 (-3350 2500)(-4075 2500);
FORCEPROP 2 LAST SIG_NAME FM_DIMM_EVENT_COD_N
J 0
(-4056 2497);
DISPLAY 0.617021 (-4056 2497);
PAINT ORANGE (-4056 2497);
WIRE 16 -1 (-3350 2250)(-3350 2500);
WIRE 16 -1 (-3350 2250)(-2900 2250);
WIRE 16 -1 (-3750 1400)(-2900 1400);
FORCEPROP 2 LAST SIG_NAME FM_ADR_COMPLETE_ABC_N
J 0
(-3700 1410);
DISPLAY 0.617021 (-3700 1410);
PAINT ORANGE (-3700 1410);
WIRE 16 -1 (-3700 1850)(-2900 1850);
FORCEPROP 2 LAST SIG_NAME SMB_DDR_ABC_VPP_SDA
J 0
(-3660 1860);
DISPLAY 0.617021 (-3660 1860);
PAINT ORANGE (-3660 1860);
WIRE 16 -1 (-3700 1800)(-2900 1800);
FORCEPROP 2 LAST SIG_NAME SMB_DDR_ABC_VPP_SCL
J 0
(-3660 1810);
DISPLAY 0.617021 (-3660 1810);
PAINT ORANGE (-3660 1810);
WIRE 16 -1 (-3750 1550)(-2900 1550);
FORCEPROP 2 LAST SIG_NAME TP_CH_C_DIMM_C1_RFU_1
J 0
(-3700 1560);
DISPLAY 0.617021 (-3700 1560);
PAINT ORANGE (-3700 1560);
FORCEPROP 2 LASTPROP $XRERR UNIQUE?
J 0
(-3990 1550);
DISPLAY 0.638298 (-3990 1550);
PAINT MONO (-3990 1550);
DISPLAY INVISIBLE (-3990 1550);
WIRE 16 -1 (-3750 1500)(-2900 1500);
FORCEPROP 2 LAST SIG_NAME TP_CH_C_DIMM_C1_RFU_0
J 0
(-3700 1510);
DISPLAY 0.617021 (-3700 1510);
PAINT ORANGE (-3700 1510);
FORCEPROP 2 LASTPROP $XRERR UNIQUE?
J 0
(-3990 1500);
DISPLAY 0.638298 (-3990 1500);
PAINT MONO (-3990 1500);
DISPLAY INVISIBLE (-3990 1500);
WIRE 16 -1 (-3750 1600)(-2900 1600);
FORCEPROP 2 LAST SIG_NAME TP_CH_C_DIMM_C1_RFU_2
J 0
(-3700 1610);
DISPLAY 0.617021 (-3700 1610);
PAINT ORANGE (-3700 1610);
FORCEPROP 2 LASTPROP $XRERR UNIQUE?
J 0
(-3990 1600);
DISPLAY 0.638298 (-3990 1600);
PAINT MONO (-3990 1600);
DISPLAY INVISIBLE (-3990 1600);
WIRE 16 -1 (-4750 1700)(-4650 1700);
WIRE 16 -1 (-4650 1700)(-4650 1600);
WIRE 16 -1 (-2900 1700)(-4650 1700);
FORCEPROP 2 LAST SIG_NAME M_C_VREF
J 0
(-3675 1710);
DISPLAY 0.617021 (-3675 1710);
PAINT ORANGE (-3675 1710);
DOT 1 (1100 2950);
DOT 1 (-800 2550);
DOT 1 (-4650 1700);
DOT 1 (1100 3250);
DOT 1 (-3100 2000);
DOT 1 (1100 2500);
DOT 1 (1100 1550);
DOT 1 (1100 1650);
DOT 1 (1100 1600);
DOT 1 (1100 1700);
DOT 1 (1100 1800);
DOT 1 (1100 1750);
DOT 1 (1100 1850);
DOT 1 (1100 1900);
DOT 1 (1100 1950);
DOT 1 (1100 2050);
DOT 1 (1100 2000);
DOT 1 (1100 2100);
DOT 1 (1100 2250);
DOT 1 (1100 2300);
DOT 1 (1100 2400);
DOT 1 (1100 2550);
DOT 1 (1100 2600);
DOT 1 (1100 2700);
DOT 1 (1100 2800);
DOT 1 (1100 2850);
DOT 1 (1100 2900);
DOT 1 (1100 3000);
DOT 1 (1100 3050);
DOT 1 (1100 3100);
DOT 1 (1100 3200);
DOT 1 (1100 3150);
DOT 1 (1100 3350);
DOT 1 (1100 3300);
DOT 1 (1100 3400);
DOT 1 (1100 3450);
DOT 1 (1100 3500);
DOT 1 (1100 3600);
DOT 1 (1100 3550);
DOT 1 (1100 3650);
DOT 1 (1100 3700);
DOT 1 (2500 1450);
DOT 1 (2500 1550);
DOT 1 (2500 1500);
DOT 1 (2500 1650);
DOT 1 (2500 1600);
DOT 1 (2500 1700);
DOT 1 (2500 1800);
DOT 1 (2500 1750);
DOT 1 (2500 1850);
DOT 1 (2500 1950);
DOT 1 (2500 2000);
DOT 1 (2500 2050);
DOT 1 (2500 2100);
DOT 1 (2500 2150);
DOT 1 (2500 2200);
DOT 1 (2500 2250);
DOT 1 (2500 2300);
DOT 1 (2500 2350);
DOT 1 (2500 2450);
DOT 1 (2500 2400);
DOT 1 (2500 2500);
DOT 1 (2500 2550);
DOT 1 (2500 2600);
DOT 1 (2500 2700);
DOT 1 (2500 2650);
DOT 1 (2500 2750);
DOT 1 (2500 2800);
DOT 1 (2500 2850);
DOT 1 (2500 2900);
DOT 1 (2500 3000);
DOT 1 (2500 3050);
DOT 1 (2500 3100);
DOT 1 (2500 3150);
DOT 1 (2500 3250);
DOT 1 (2500 3200);
DOT 1 (2500 3350);
DOT 1 (2500 3300);
DOT 1 (2500 3400);
DOT 1 (2500 3450);
DOT 1 (2500 3500);
DOT 1 (2500 3550);
DOT 1 (2500 3600);
DOT 1 (2500 3650);
DOT 1 (2500 3700);
DOT 1 (1100 1500);
DOT 1 (1100 2450);
DOT 1 (1100 2350);
DOT 1 (-800 2700);
DOT 1 (-800 2750);
DOT 1 (-800 2850);
DOT 1 (-800 2800);
DOT 1 (-800 2250);
DOT 1 (-800 2200);
DOT 1 (-800 2300);
DOT 1 (-800 2350);
DOT 1 (-800 2400);
DOT 1 (-800 2150);
DOT 1 (-800 1750);
DOT 1 (-800 1800);
DOT 1 (-800 1850);
DOT 1 (-800 1900);
DOT 1 (-800 1950);
DOT 1 (-800 2050);
DOT 1 (-800 2000);
DOT 1 (-800 2100);
DOT 1 (-800 1650);
DOT 1 (-800 1200);
DOT 1 (-800 1250);
DOT 1 (-800 1350);
DOT 1 (-800 1450);
DOT 1 (-800 1500);
DOT 1 (-800 1550);
DOT 1 (-800 1400);
DOT 1 (-800 1600);
DOT 1 (-800 1300);
DOT 1 (-800 1700);
DOT 1 (1100 2750);
DOT 1 (600 2850);
DOT 1 (1100 2150);
DOT 1 (1100 2200);
DOT 1 (1100 1450);
DOT 1 (2500 1900);
DOT 1 (-3100 2050);
DOT 1 (2500 2950);
DOT 1 (1100 2650);
FORCENOTE
PVDDQ (SINGLE SIDE) CAP: 10UF X1, 22UF X50
(-3900 5200) 0;
DISPLAY LEFT (-3900 5200);
DISPLAY 1.021277 (-3900 5200);
PAINT PURPLE (-3900 5200);
FORCENOTE
PVTT CAP: 100UF X2, 47UF X1
(-3900 5250) 0;
DISPLAY LEFT (-3900 5250);
DISPLAY 1.021277 (-3900 5250);
PAINT PURPLE (-3900 5250);
FORCENOTE
PVDDQ (DOUBLE SIDE) CAP: 100UF X8, 47UF X41
(-3900 5150) 0;
DISPLAY LEFT (-3900 5150);
DISPLAY 1.021277 (-3900 5150);
PAINT PURPLE (-3900 5150);
FORCENOTE
SMBUS ADDR: 0XAA
(-5286 742) 0;
DISPLAY LEFT (-5286 742);
DISPLAY 1.574468 (-5286 742);
PAINT PURPLE (-5286 742);
FORCENOTE
PLACE CAP NEAR DIMM CONNECTOR
(-5288 927) 0;
DISPLAY LEFT (-5288 927);
DISPLAY 1.595745 (-5288 927);
PAINT PURPLE (-5288 927);
FORCENOTE
CAP BETWEEN DIMM
(-3900 5375) 0;
DISPLAY LEFT (-3900 5375);
DISPLAY 1.276596 (-3900 5375);
PAINT PURPLE (-3900 5375);
FORCENOTE
PVPP CAP: 10UF X12
(-3900 5300) 0;
DISPLAY LEFT (-3900 5300);
DISPLAY 1.021277 (-3900 5300);
PAINT PURPLE (-3900 5300);
QUIT
